G04 ================== begin FILE IDENTIFICATION RECORD ==================*
G04 Layout Name:  9049_F0T_FAN_BOARD_MP5048_D_v02_20221209_0830.brd*
G04 Film Name:    in2*
G04 File Format:  Gerber RS274X*
G04 File Origin:  Cadence Allegro 17.2-S081*
G04 Origin Date:  Mon Dec 12 15:05:04 2022*
G04 *
G04 Layer:  DRAWING FORMAT/TITLE_BLOCK_A*
G04 Layer:  PIN/SPECIAL_DRILL*
G04 Layer:  DRAWING FORMAT/TITLE_DATA_IN2*
G04 Layer:  VIA CLASS/IN2*
G04 Layer:  PIN/IN2*
G04 Layer:  MANUFACTURING/PHOTOPLOT_OUTLINE*
G04 Layer:  ETCH/IN2*
G04 Layer:  DRAWING FORMAT/TITLE_BLOCK*
G04 *
G04 Offset:    (0.00 0.00)*
G04 Mirror:    No*
G04 Mode:      Positive*
G04 Rotation:  0*
G04 FullContactRelief:  No*
G04 UndefLineWidth:     6.00*
G04 ================== end FILE IDENTIFICATION RECORD ====================*
%FSLAX25Y25*MOIN*%
%IR0*IPPOS*OFA0.00000B0.00000*MIA0B0*SFA1.00000B1.00000*%
%ADD11C,.02*%
%ADD10C,.085*%
%ADD12C,.006*%
%ADD13C,.009*%
%ADD16C,.07004*%
%ADD17C,.45004*%
%ADD15C,.16506*%
%ADD14O,.35438X.82683*%
G75*
%LPD*%
G75*
G36*
G01X176162Y1320271D02*
X187795D01*
G02X192532Y1318966I1J-9247D01*
G02X192540Y1318961I-102J-172D01*
G03X192736Y1318840I1937J2918D01*
G02X192744Y1318835I-102J-172D01*
G02X197042Y1311024I-4949J-7811D01*
G01Y1309289D01*
G03X197034Y1309059I3494J-237D01*
G03X197042Y1308829I3502J7D01*
G01Y1289289D01*
G03X197034Y1289059I3494J-237D01*
G03X197042Y1288829I3502J7D01*
G01Y1269289D01*
G03X197034Y1269059I3494J-237D01*
G03X197042Y1268829I3502J7D01*
G01Y1249289D01*
G03X197034Y1249059I3494J-237D01*
G03X197042Y1248829I3502J7D01*
G01Y1229289D01*
G03X197034Y1229059I3494J-237D01*
G03X197042Y1228829I3502J7D01*
G01Y1226231D01*
G02X196961Y1226070I-200J0D01*
G01X196664Y1225851D01*
X196571Y1225835D01*
X196525Y1225849D01*
G03X195500Y1226002I-1024J-3349D01*
G03X191998Y1222500I0J-3502D01*
G03X192204Y1221318I3502J1D01*
G02Y1221182I-189J-68D01*
G03X191998Y1220000I3296J-1183D01*
G03X192158Y1218954I3502J0D01*
G01X192171Y1218912D01*
X192161Y1218829D01*
X191962Y1218497D01*
X191893Y1218449D01*
X191850Y1218441D01*
G03X188998Y1215000I650J-3441D01*
G03X196002I3502J0D01*
G03X195842Y1216046I-3502J0D01*
G01X195829Y1216088D01*
X195839Y1216171D01*
X196038Y1216503D01*
X196107Y1216551D01*
X196150Y1216559D01*
G03X196525Y1216651I-646J3442D01*
G01X196571Y1216665D01*
X196664Y1216649D01*
X196961Y1216430D01*
G02X197042Y1216269I-119J-161D01*
G01Y1209289D01*
G03X197034Y1209059I3494J-237D01*
G03X197042Y1208829I3502J7D01*
G01Y1189289D01*
G03X197034Y1189059I3494J-237D01*
G03X197042Y1188829I3502J7D01*
G01Y1169289D01*
G03X197034Y1169059I3494J-237D01*
G03X197042Y1168829I3502J7D01*
G01Y1149289D01*
G03X197034Y1149059I3494J-237D01*
G03X197042Y1148829I3502J7D01*
G01Y1129289D01*
G03X197034Y1129059I3494J-237D01*
G03X197042Y1128829I3502J7D01*
G01Y1109289D01*
G03X197034Y1109059I3494J-237D01*
G03X197042Y1108829I3502J7D01*
G01Y1089289D01*
G03X197034Y1089059I3494J-237D01*
G03X197042Y1088829I3502J7D01*
G01Y1069289D01*
G03X197034Y1069059I3494J-237D01*
G03X197042Y1068829I3502J7D01*
G01Y1049289D01*
G03X197034Y1049059I3494J-237D01*
G03X197042Y1048829I3502J7D01*
G01Y1029289D01*
G03X197034Y1029059I3494J-237D01*
G03X197042Y1028829I3502J7D01*
G01Y1009289D01*
G03X197034Y1009059I3494J-237D01*
G03X197042Y1008829I3502J7D01*
G01Y989289D01*
G03X197034Y989059I3494J-237D01*
G03X197042Y988829I3502J7D01*
G01Y969289D01*
G03X197034Y969059I3494J-237D01*
G03X197042Y968829I3502J7D01*
G01Y947289D01*
G03X197034Y947059I3494J-237D01*
G03X197042Y946829I3502J7D01*
G01Y929289D01*
G03X197034Y929059I3494J-237D01*
G03X197042Y928829I3502J7D01*
G01Y909289D01*
G03X197034Y909059I3494J-237D01*
G03X197042Y908829I3502J7D01*
G01Y901853D01*
G02X196921Y901669I-200J0D01*
G01X196528Y901500D01*
X196412Y901520D01*
X196368Y901562D01*
G03X193964Y902517I-2404J-2548D01*
G03X190462Y899015I0J-3502D01*
G03X190762Y897596I3502J-1D01*
G02Y897434I-182J-81D01*
G03X190462Y896015I3202J-1418D01*
G03X190762Y894596I3502J-1D01*
G02Y894434I-182J-81D01*
G03X190462Y893015I3202J-1418D01*
G03X190762Y891596I3502J-1D01*
G02Y891434I-182J-81D01*
G03X190462Y890015I3202J-1418D01*
G03X190762Y888596I3502J-1D01*
G02Y888434I-182J-81D01*
G03X190462Y887015I3202J-1418D01*
G03X193964Y883513I3502J0D01*
G03X196368Y884468I0J3503D01*
G01X196412Y884510D01*
X196528Y884530D01*
X196921Y884361D01*
G02X197042Y884177I-79J-184D01*
G01Y869289D01*
G03X197034Y869059I3494J-237D01*
G03X197042Y868829I3502J7D01*
G01Y849289D01*
G03X197034Y849059I3494J-237D01*
G03X197042Y848829I3502J7D01*
G01Y829289D01*
G03X197034Y829059I3494J-237D01*
G03X197042Y828829I3502J7D01*
G01Y809289D01*
G03X197034Y809059I3494J-237D01*
G03X197042Y808829I3502J7D01*
G01Y789289D01*
G03X197034Y789059I3494J-237D01*
G03X197042Y788829I3502J7D01*
G01Y769289D01*
G03X197034Y769059I3494J-237D01*
G03X197042Y768829I3502J7D01*
G01Y756040D01*
G02X196950Y755871I-200J-1D01*
G01X196622Y755662D01*
X196521Y755655D01*
X196474Y755677D01*
G03X196343Y755734I-1462J-3182D01*
G02X196234Y755843I76J185D01*
G03X194343Y757734I-3234J-1343D01*
G02X194234Y757843I76J185D01*
G03X192343Y759734I-3234J-1343D01*
G02X192234Y759843I76J185D01*
G03X189000Y762002I-3234J-1343D01*
G03X185498Y758500I0J-3502D01*
G03X187657Y755266I3502J0D01*
G02X187766Y755157I-76J-185D01*
G03X189657Y753266I3234J1343D01*
G02X189766Y753157I-76J-185D01*
G03X191657Y751266I3234J1343D01*
G02X191766Y751157I-76J-185D01*
G03X195000Y748998I3234J1343D01*
G03X196468Y749320I1J3502D01*
G01X196514Y749342D01*
X196614Y749335D01*
X196984Y749106D01*
X197034Y749018D01*
X197035Y748968D01*
G03X197042Y748829I3500J107D01*
G01Y729289D01*
G03X197034Y729059I3494J-237D01*
G03X197042Y728829I3502J7D01*
G01Y709289D01*
G03X197034Y709059I3494J-237D01*
G03X197042Y708829I3502J7D01*
G01Y708279D01*
G02X196903Y708089I-200J0D01*
G01X196479Y707952D01*
X196356Y707992D01*
X196317Y708046D01*
G03X193475Y709502I-2842J-2046D01*
G03Y702498I0J-3502D01*
G03X196317Y703954I0J3502D01*
G01X196356Y704008D01*
X196479Y704048D01*
X196903Y703911D01*
G02X197042Y703721I-61J-190D01*
G01Y689289D01*
G03X197034Y689059I3494J-237D01*
G03X197042Y688829I3502J7D01*
G01Y669289D01*
G03X197034Y669059I3494J-237D01*
G03X197042Y668829I3502J7D01*
G01Y649289D01*
G03X197034Y649059I3494J-237D01*
G03X197042Y648829I3502J7D01*
G01Y629289D01*
G03X197034Y629059I3494J-237D01*
G03X197042Y628829I3502J7D01*
G01Y609289D01*
G03X197034Y609059I3494J-237D01*
G03X197042Y608829I3502J7D01*
G01Y589289D01*
G03X197034Y589059I3494J-237D01*
G03X197042Y588829I3502J7D01*
G01Y569289D01*
G03X197034Y569059I3494J-237D01*
G03X197042Y568829I3502J7D01*
G01Y552871D01*
G02X196922Y552688I-200J0D01*
G01X196532Y552517D01*
X196415Y552537D01*
X196371Y552577D01*
G03X194000Y553502I-2371J-2576D01*
G03X190661Y551057I0J-3502D01*
G02X190513Y550922I-190J60D01*
G03X187757Y547500I746J-3422D01*
G03X188291Y545642I3502J1D01*
G01X188315Y545603D01*
X188325Y545513D01*
X188192Y545132D01*
X188128Y545068D01*
X188085Y545052D01*
G03X185748Y541750I1164J-3302D01*
G03X188516Y538326I3502J0D01*
G01X188560Y538316D01*
X188631Y538261D01*
X188813Y537903D01*
X188815Y537812D01*
X188796Y537771D01*
G03X188489Y536336I3195J-1434D01*
G03X190100Y533388I3503J0D01*
G01X190147Y533358D01*
X190196Y533261D01*
X190162Y532800D01*
X190101Y532711D01*
X190050Y532688D01*
G03X187998Y529500I1450J-3188D01*
G03X189050Y526998I3501J0D01*
G01X189079Y526970D01*
X189109Y526898D01*
X189114Y526536D01*
X189085Y526463D01*
X189057Y526434D01*
G03X188073Y524000I2518J-2434D01*
G03X188472Y522377I3502J0D01*
G01X188495Y522333D01*
X188494Y522234D01*
X188290Y521854D01*
X188208Y521799D01*
X188158Y521794D01*
G03X185014Y518310I358J-3484D01*
G03X186969Y515168I3502J0D01*
G01X187013Y515147D01*
X187071Y515068D01*
X187136Y514648D01*
X187105Y514555D01*
X187070Y514521D01*
G03X185998Y512000I2430J-2522D01*
G03X193002I3502J0D01*
G03X192050Y514400I-3501J0D01*
G01X192013Y514440D01*
X191989Y514546D01*
X192128Y514983D01*
X192209Y515056D01*
X192263Y515066D01*
G03X195077Y518500I-688J3434D01*
G03X194059Y520968I-3501J0D01*
G01X194031Y520997D01*
X194001Y521069D01*
Y521431D01*
X194031Y521503D01*
X194059Y521532D01*
G03X195077Y524000I-2483J2468D01*
G03X194025Y526502I-3501J0D01*
G01X193996Y526530D01*
X193966Y526602D01*
X193961Y526964D01*
X193990Y527037D01*
X194018Y527066D01*
G03X195002Y529500I-2518J2434D01*
G03X193391Y532448I-3503J0D01*
G01X193344Y532478D01*
X193295Y532575D01*
X193329Y533036D01*
X193390Y533125D01*
X193441Y533148D01*
G03X195493Y536336I-1450J3188D01*
G03X192725Y539760I-3502J0D01*
G01X192681Y539770D01*
X192610Y539825D01*
X192428Y540183D01*
X192426Y540274D01*
X192445Y540315D01*
G03X192752Y541750I-3195J1434D01*
G03X192218Y543608I-3502J-1D01*
G01X192194Y543647D01*
X192184Y543737D01*
X192317Y544118D01*
X192381Y544182D01*
X192424Y544198D01*
G03X194598Y546443I-1164J3303D01*
G02X194746Y546578I190J-60D01*
G03X196371Y547423I-747J3421D01*
G01X196415Y547463D01*
X196532Y547483D01*
X196922Y547312D01*
G02X197042Y547129I-80J-183D01*
G01Y529289D01*
G03X197034Y529059I3494J-237D01*
G03X197042Y528829I3502J7D01*
G01Y509289D01*
G03X197034Y509059I3494J-237D01*
G03X197042Y508829I3502J7D01*
G01Y501231D01*
G02X196961Y501070I-200J0D01*
G01X196664Y500851D01*
X196571Y500835D01*
X196525Y500849D01*
G03X195500Y501002I-1024J-3349D01*
G03X191998Y497500I0J-3502D01*
G03X192204Y496318I3502J1D01*
G02Y496182I-189J-68D01*
G03X191998Y495000I3296J-1183D01*
G03X192510Y493178I3502J1D01*
G02X192483Y492934I-171J-105D01*
G03X191498Y490500I2517J-2435D01*
G03X195000Y486998I3502J0D01*
G03X196474Y487323I1J3502D01*
G01X196521Y487345D01*
X196622Y487338D01*
X196950Y487129D01*
G02X197042Y486960I-108J-168D01*
G01Y469289D01*
G03X197034Y469059I3494J-237D01*
G03X197042Y468829I3502J7D01*
G01Y449289D01*
G03X197034Y449059I3494J-237D01*
G03X197042Y448829I3502J7D01*
G01Y429289D01*
G03X197034Y429059I3494J-237D01*
G03X197042Y428829I3502J7D01*
G01Y409289D01*
G03X197034Y409059I3494J-237D01*
G03X197042Y408829I3502J7D01*
G01Y389289D01*
G03X197034Y389059I3494J-237D01*
G03X197042Y388829I3502J7D01*
G01Y369289D01*
G03X197034Y369059I3494J-237D01*
G03X197042Y368829I3502J7D01*
G01Y349289D01*
G03X197034Y349059I3494J-237D01*
G03X197042Y348829I3502J7D01*
G01Y329289D01*
G03X197034Y329059I3494J-237D01*
G03X197042Y328829I3502J7D01*
G01Y309289D01*
G03X197034Y309059I3494J-237D01*
G03X197042Y308829I3502J7D01*
G01Y289289D01*
G03X197034Y289059I3494J-237D01*
G03X197042Y288829I3502J7D01*
G01Y269289D01*
G03X197034Y269059I3494J-237D01*
G03X197042Y268829I3502J7D01*
G01Y249289D01*
G03X197034Y249059I3494J-237D01*
G03X197042Y248829I3502J7D01*
G01Y229289D01*
G03X197034Y229059I3494J-237D01*
G03X197042Y228829I3502J7D01*
G01Y209289D01*
G03X197034Y209059I3494J-237D01*
G03X197042Y208829I3502J7D01*
G01Y189289D01*
G03X197034Y189059I3494J-237D01*
G03X197042Y188829I3502J7D01*
G01Y169289D01*
G03X197034Y169059I3494J-237D01*
G03X197042Y168829I3502J7D01*
G01Y160074D01*
G02X196913Y159887I-200J0D01*
G01X196504Y159732D01*
X196384Y159762D01*
X196342Y159809D01*
G03X193719Y160991I-2623J-2319D01*
G03X192537Y160785I1J-3502D01*
G02X192401I-68J189D01*
G03X191219Y160991I-1183J-3296D01*
G03Y153987I0J-3502D01*
G03X192401Y154193I-1J3502D01*
G02X192537I68J-189D01*
G03X193719Y153987I1183J3296D01*
G03X196342Y155169I0J3501D01*
G01X196384Y155216D01*
X196504Y155246D01*
X196913Y155091D01*
G02X197042Y154904I-71J-187D01*
G01Y149289D01*
G03X197034Y149059I3494J-237D01*
G03X197042Y148829I3502J7D01*
G01Y129289D01*
G03X197034Y129059I3494J-237D01*
G03X197042Y128829I3502J7D01*
G01Y109289D01*
G03X197034Y109059I3494J-237D01*
G03X197042Y108829I3502J7D01*
G01Y89289D01*
G03X197034Y89059I3494J-237D01*
G03X197042Y88829I3502J7D01*
G01Y69289D01*
G03X197034Y69059I3494J-237D01*
G03X197042Y68829I3502J7D01*
G01Y49289D01*
G03X197034Y49059I3494J-237D01*
G03X197042Y48829I3502J7D01*
G01Y29289D01*
G03X197034Y29059I3494J-237D01*
G03X197042Y28829I3502J7D01*
G01Y15748D01*
G02X196084Y11649I-9248J0D01*
G02X196078Y11638I-179J90D01*
G03X195943Y11377I3040J-1738D01*
G02X195938Y11366I-184J77D01*
G02X187795Y6501I-8143J4382D01*
G01X185940D01*
G03X185799Y6504I-145J-3499D01*
G03X185658Y6501I4J-3502D01*
G01X165940D01*
G03X165799Y6504I-145J-3499D01*
G03X165658Y6501I4J-3502D01*
G01X147422D01*
G02X147280Y6560I0J200D01*
G01X145300Y8540D01*
G02X145241Y8682I141J142D01*
G01Y26678D01*
G03X145250Y26922I-3493J251D01*
G03X145241Y27166I-3502J-7D01*
G01Y43307D01*
G03X135811Y54388I-11226J0D01*
G02X135798Y54390I24J198D01*
G03X135129Y54477I-784J-3413D01*
G02X135116Y54478I9J200D01*
G03X134016Y54532I-1100J-11171D01*
G01X119115D01*
G03X118973Y54473I0J-200D01*
G01X117274Y52774D01*
G03X117215Y52632I141J-142D01*
G01Y34275D01*
G02X117156Y34133I-200J0D01*
G01X116782Y33759D01*
G02X116640Y33700I-142J141D01*
G01X111283D01*
G02X111141Y33759I0J200D01*
G01X110659Y34241D01*
G02X110600Y34383I141J142D01*
G01Y45417D01*
G03X110541Y45559I-200J0D01*
G01X104659Y51441D01*
G03X104517Y51500I-142J-141D01*
G01X97083D01*
G02X96941Y51559I0J200D01*
G01X94027Y54473D01*
G03X93885Y54532I-142J-141D01*
G01X86402D01*
G02X86217Y54656I0J200D01*
G03X79733I-3242J-1322D01*
G02X79548Y54532I-185J76D01*
G01X69632D01*
G03X68297Y54465I-106J-11225D01*
G02X68288Y54464I-27J198D01*
G03X67806Y54400I219J-3495D01*
G02X67797Y54398I-48J194D01*
G03X58302Y43307I1730J-11091D01*
G01Y26042D01*
G03X58300Y25927I3500J-118D01*
G03X58302Y25812I3502J3D01*
G01Y8681D01*
G02X58243Y8539I-200J0D01*
G01X56264Y6560D01*
G02X56122Y6501I-142J141D01*
G01X55142D01*
G03X54927Y6508I-221J-3495D01*
G03X54712Y6501I6J-3502D01*
G01X35142D01*
G03X34927Y6508I-221J-3495D01*
G03X34712Y6501I6J-3502D01*
G01X16145D01*
X16138Y6502D01*
G03X15868Y6512I-265J-3492D01*
G03X15614Y6503I-3J-3502D01*
G02X15596Y6502I-20J199D01*
G02X6501Y15748I152J9246D01*
G01Y30476D01*
G03X6507Y30675I-3496J205D01*
G03X6501Y30874I-3502J-6D01*
G01Y40144D01*
G02X6571Y40296I200J0D01*
G01X6835Y40522D01*
X6919Y40546D01*
X6962Y40540D01*
G03X7500Y40498I541J3460D01*
G03Y47502I0J3502D01*
G03X6962Y47460I3J-3502D01*
G01X6919Y47454D01*
X6835Y47478D01*
X6571Y47704D01*
G02X6501Y47856I130J152D01*
G01Y50476D01*
G03X6507Y50675I-3496J205D01*
G03X6501Y50874I-3502J-6D01*
G01Y70476D01*
G03X6507Y70675I-3496J205D01*
G03X6501Y70874I-3502J-6D01*
G01Y90476D01*
G03X6507Y90675I-3496J205D01*
G03X6501Y90874I-3502J-6D01*
G01Y110476D01*
G03X6507Y110675I-3496J205D01*
G03X6501Y110874I-3502J-6D01*
G01Y130476D01*
G03X6507Y130675I-3496J205D01*
G03X6501Y130874I-3502J-6D01*
G01Y150476D01*
G03X6507Y150675I-3496J205D01*
G03X6501Y150874I-3502J-6D01*
G01Y156897D01*
G02X6602Y157071I200J0D01*
G01X6953Y157269D01*
X7060Y157268D01*
X7107Y157240D01*
G03X8337Y156788I1802J3003D01*
G01X8383Y156780D01*
X8457Y156728D01*
X8654Y156372D01*
X8659Y156283D01*
X8641Y156239D01*
G03X8372Y154893I3233J-1346D01*
G03X15376I3502J0D01*
G03X12445Y158348I-3502J0D01*
G01X12399Y158356D01*
X12325Y158408D01*
X12128Y158764D01*
X12123Y158853D01*
X12141Y158897D01*
G03X12410Y160243I-3233J1346D01*
G03X12110Y161662I-3502J1D01*
G02Y161824I182J81D01*
G03X12410Y163243I-3202J1418D01*
G03X8908Y166745I-3502J0D01*
G03X7107Y166246I1J-3502D01*
G01X7060Y166218D01*
X6953Y166217D01*
X6602Y166415D01*
G02X6501Y166589I99J174D01*
G01Y170476D01*
G03X6507Y170675I-3496J205D01*
G03X6501Y170874I-3502J-6D01*
G01Y190476D01*
G03X6507Y190675I-3496J205D01*
G03X6501Y190874I-3502J-6D01*
G01Y210476D01*
G03X6507Y210675I-3496J205D01*
G03X6501Y210874I-3502J-6D01*
G01Y230476D01*
G03X6507Y230675I-3496J205D01*
G03X6501Y230874I-3502J-6D01*
G01Y238519D01*
G02X6616Y238700I200J0D01*
G01X6998Y238879D01*
X7112Y238864D01*
X7157Y238826D01*
G03X9400Y238014I2242J2690D01*
G03Y245018I0J3502D01*
G03X7157Y244206I-1J-3502D01*
G01X7112Y244168D01*
X6998Y244153D01*
X6616Y244332D01*
G02X6501Y244513I85J181D01*
G01Y250476D01*
G03X6507Y250675I-3496J205D01*
G03X6501Y250874I-3502J-6D01*
G01Y264932D01*
G02X6637Y265121I200J0D01*
G01X7057Y265264D01*
X7179Y265226D01*
X7219Y265175D01*
G03X9751Y263810I2781J2128D01*
G01X9807Y263806D01*
X9897Y263743D01*
X10086Y263317D01*
X10072Y263208D01*
X10037Y263164D01*
G03X9289Y261000I2754J-2163D01*
G03X16293I3502J0D01*
G03X13040Y264493I-3502J0D01*
G01X12984Y264497D01*
X12894Y264560D01*
X12705Y264986D01*
X12719Y265095D01*
X12754Y265139D01*
G03X13502Y267303I-2754J2163D01*
G03X11556Y270440I-3501J0D01*
G01X11502Y270467D01*
X11442Y270572D01*
X11476Y271063D01*
X11550Y271159D01*
X11608Y271178D01*
G03X14002Y274500I-1108J3322D01*
G03X6998I-3502J0D01*
G03X8944Y271363I3501J0D01*
G01X8998Y271336D01*
X9058Y271231D01*
X9024Y270740D01*
X8950Y270644D01*
X8892Y270625D01*
G03X7219Y269431I1108J-3322D01*
G01X7179Y269380D01*
X7057Y269342D01*
X6637Y269485D01*
G02X6501Y269674I64J189D01*
G01Y270476D01*
G03X6507Y270675I-3496J205D01*
G03X6501Y270874I-3502J-6D01*
G01Y290476D01*
G03X6507Y290675I-3496J205D01*
G03X6501Y290874I-3502J-6D01*
G01Y310476D01*
G03X6507Y310675I-3496J205D01*
G03X6501Y310874I-3502J-6D01*
G01Y330476D01*
G03X6507Y330675I-3496J205D01*
G03X6501Y330874I-3502J-6D01*
G01Y350476D01*
G03X6507Y350675I-3496J205D01*
G03X6501Y350874I-3502J-6D01*
G01Y370476D01*
G03X6507Y370675I-3496J205D01*
G03X6501Y370874I-3502J-6D01*
G01Y390476D01*
G03X6507Y390675I-3496J205D01*
G03X6501Y390874I-3502J-6D01*
G01Y410476D01*
G03X6507Y410675I-3496J205D01*
G03X6501Y410874I-3502J-6D01*
G01Y430476D01*
G03X6507Y430675I-3496J205D01*
G03X6501Y430874I-3502J-6D01*
G01Y450476D01*
G03X6507Y450675I-3496J205D01*
G03X6501Y450874I-3502J-6D01*
G01Y470476D01*
G03X6507Y470675I-3496J205D01*
G03X6501Y470874I-3502J-6D01*
G01Y490476D01*
G03X6507Y490675I-3496J205D01*
G03X6501Y490874I-3502J-6D01*
G01Y510476D01*
G03X6507Y510675I-3496J205D01*
G03X6501Y510874I-3502J-6D01*
G01Y530476D01*
G03X6507Y530675I-3496J205D01*
G03X6501Y530874I-3502J-6D01*
G01Y550476D01*
G03X6507Y550675I-3496J205D01*
G03X6501Y550874I-3502J-6D01*
G01Y570476D01*
G03X6507Y570675I-3496J205D01*
G03X6501Y570874I-3502J-6D01*
G01Y590476D01*
G03X6507Y590675I-3496J205D01*
G03X6501Y590874I-3502J-6D01*
G01Y610476D01*
G03X6507Y610675I-3496J205D01*
G03X6501Y610874I-3502J-6D01*
G01Y630476D01*
G03X6507Y630675I-3496J205D01*
G03X6501Y630874I-3502J-6D01*
G01Y650476D01*
G03X6507Y650675I-3496J205D01*
G03X6501Y650874I-3502J-6D01*
G01Y670476D01*
G03X6507Y670675I-3496J205D01*
G03X6501Y670874I-3502J-6D01*
G01Y690476D01*
G03X6507Y690675I-3496J205D01*
G03X6501Y690874I-3502J-6D01*
G01Y710476D01*
G03X6507Y710675I-3496J205D01*
G03X6501Y710874I-3502J-6D01*
G01Y723437D01*
X6592Y723548D01*
X6663Y723561D01*
G03X9502Y727000I-663J3439D01*
G03X7559Y730136I-3502J0D01*
G01X7508Y730161D01*
X7448Y730258D01*
X7450Y730732D01*
X7510Y730828D01*
X7562Y730853D01*
G03X9527Y734000I-1538J3147D01*
G03X7573Y737141I-3502J0D01*
G02X7462Y737321I89J179D01*
G01Y737679D01*
G02X7573Y737859I200J1D01*
G03X9527Y741000I-1548J3141D01*
G03X7573Y744141I-3502J0D01*
G02X7462Y744321I89J179D01*
G01Y744679D01*
G02X7573Y744859I200J1D01*
G03X9527Y748000I-1548J3141D01*
G03X6664Y751443I-3502J0D01*
G01X6592Y751456D01*
X6501Y751566D01*
Y770476D01*
G03X6507Y770675I-3496J205D01*
G03X6501Y770874I-3502J-6D01*
G01Y790476D01*
G03X6507Y790675I-3496J205D01*
G03X6501Y790874I-3502J-6D01*
G01Y810476D01*
G03X6507Y810675I-3496J205D01*
G03X6501Y810874I-3502J-6D01*
G01Y830476D01*
G03X6507Y830675I-3496J205D01*
G03X6501Y830874I-3502J-6D01*
G01Y850476D01*
G03X6507Y850675I-3496J205D01*
G03X6501Y850874I-3502J-6D01*
G01Y870476D01*
G03X6507Y870675I-3496J205D01*
G03X6501Y870874I-3502J-6D01*
G01Y890476D01*
G03X6507Y890675I-3496J205D01*
G03X6501Y890874I-3502J-6D01*
G01Y910476D01*
G03X6507Y910675I-3496J205D01*
G03X6501Y910874I-3502J-6D01*
G01Y930476D01*
G03X6507Y930675I-3496J205D01*
G03X6501Y930874I-3502J-6D01*
G01Y950476D01*
G03X6507Y950675I-3496J205D01*
G03X6501Y950874I-3502J-6D01*
G01Y970476D01*
G03X6507Y970675I-3496J205D01*
G03X6501Y970874I-3502J-6D01*
G01Y990476D01*
G03X6507Y990675I-3496J205D01*
G03X6501Y990874I-3502J-6D01*
G01Y992160D01*
G02X6631Y992347I200J0D01*
G01X7040Y992501D01*
X7161Y992470D01*
X7202Y992423D01*
G03X9838Y991227I2636J2307D01*
G03X12627Y992611I0J3502D01*
G01X12652Y992643D01*
X12719Y992683D01*
X13077Y992734D01*
X13152Y992714D01*
X13185Y992690D01*
G03X15275Y991998I2090J2810D01*
G03X18777Y995500I0J3502D01*
G03X17489Y998214I-3503J0D01*
G01X17455Y998241D01*
X17417Y998316D01*
X17399Y998699D01*
X17430Y998778D01*
X17461Y998808D01*
G03X18502Y1001300I-2462J2492D01*
G03X11498I-3502J0D01*
G03X12786Y998586I3503J0D01*
G01X12820Y998559D01*
X12858Y998484D01*
X12876Y998101D01*
X12845Y998022D01*
X12814Y997992D01*
G03X12486Y997618I2462J-2490D01*
G01X12461Y997586D01*
X12394Y997546D01*
X12036Y997495D01*
X11961Y997515D01*
X11928Y997539D01*
G03X9838Y998231I-2090J-2810D01*
G03X7202Y997035I0J-3503D01*
G01X7161Y996988D01*
X7040Y996957D01*
X6631Y997111D01*
G02X6501Y997298I70J187D01*
G01Y1010476D01*
G03X6507Y1010675I-3496J205D01*
G03X6501Y1010874I-3502J-6D01*
G01Y1030476D01*
G03X6507Y1030675I-3496J205D01*
G03X6501Y1030874I-3502J-6D01*
G01Y1050476D01*
G03X6507Y1050675I-3496J205D01*
G03X6501Y1050874I-3502J-6D01*
G01Y1070476D01*
G03X6507Y1070675I-3496J205D01*
G03X6501Y1070874I-3502J-6D01*
G01Y1090476D01*
G03X6507Y1090675I-3496J205D01*
G03X6501Y1090874I-3502J-6D01*
G01Y1110476D01*
G03X6507Y1110675I-3496J205D01*
G03X6501Y1110874I-3502J-6D01*
G01Y1130476D01*
G03X6507Y1130675I-3496J205D01*
G03X6501Y1130874I-3502J-6D01*
G01Y1150476D01*
G03X6507Y1150675I-3496J205D01*
G03X6501Y1150874I-3502J-6D01*
G01Y1170476D01*
G03X6507Y1170675I-3496J205D01*
G03X6501Y1170874I-3502J-6D01*
G01Y1190476D01*
G03X6507Y1190675I-3496J205D01*
G03X6501Y1190874I-3502J-6D01*
G01Y1210476D01*
G03X6507Y1210675I-3496J205D01*
G03X6501Y1210874I-3502J-6D01*
G01Y1216256D01*
G02X6581Y1216416I200J0D01*
G01X6876Y1216637D01*
X6967Y1216653D01*
X7014Y1216640D01*
G03X7350Y1216559I988J3360D01*
G01X7393Y1216551D01*
X7462Y1216503D01*
X7661Y1216171D01*
X7671Y1216088D01*
X7658Y1216046D01*
G03X7498Y1215000I3342J-1046D01*
G03X14502I3502J0D01*
G03X11650Y1218441I-3502J0D01*
G01X11607Y1218449D01*
X11538Y1218497D01*
X11339Y1218829D01*
X11329Y1218912D01*
X11342Y1218954D01*
G03X11502Y1220000I-3342J1046D01*
G03X11296Y1221182I-3502J-1D01*
G02Y1221318I189J68D01*
G03X11502Y1222500I-3296J1183D01*
G03X11238Y1223834I-3502J0D01*
G01X11218Y1223883D01*
X11232Y1223990D01*
X11511Y1224349D01*
X11610Y1224389D01*
X11664Y1224382D01*
G03X12150Y1224348I487J3468D01*
G03X15652Y1227850I0J3502D01*
G03X13093Y1231223I-3502J0D01*
G01X13044Y1231236D01*
X12971Y1231308D01*
X12843Y1231730D01*
X12864Y1231829D01*
X12898Y1231868D01*
G03X13743Y1234150I-2657J2281D01*
G03X13083Y1236196I-3501J0D01*
G01X13060Y1236228D01*
X13042Y1236302D01*
X13092Y1236654D01*
X13130Y1236720D01*
X13161Y1236744D01*
G03X14502Y1239500I-2162J2756D01*
G03X7498I-3502J0D01*
G03X8158Y1237454I3501J0D01*
G01X8181Y1237422D01*
X8199Y1237348D01*
X8149Y1236996D01*
X8111Y1236930D01*
X8080Y1236906D01*
G03X6952Y1235351I2162J-2755D01*
G01X6936Y1235310D01*
X6905Y1235279D01*
G02X6622I-141J141D01*
G01X6560Y1235341D01*
G02X6501Y1235483I141J142D01*
G01Y1250476D01*
G03X6507Y1250675I-3496J205D01*
G03X6501Y1250874I-3502J-6D01*
G01Y1270476D01*
G03X6507Y1270675I-3496J205D01*
G03X6501Y1270874I-3502J-6D01*
G01Y1290476D01*
G03X6507Y1290675I-3496J205D01*
G03X6501Y1290874I-3502J-6D01*
G01Y1310476D01*
G03X6507Y1310675I-3496J205D01*
G03X6501Y1310874I-3502J-6D01*
G01Y1311024D01*
G02X15748Y1320271I9247J0D01*
G01X15876D01*
G03X16017Y1320268I145J3499D01*
G03X16158Y1320271I-4J3502D01*
G01X35376D01*
G03X35517Y1320268I145J3499D01*
G03X35658Y1320271I-4J3502D01*
G01X55876D01*
G03X56017Y1320268I145J3499D01*
G03X56158Y1320271I-4J3502D01*
G01X75876D01*
G03X76017Y1320268I145J3499D01*
G03X76158Y1320271I-4J3502D01*
G01X95876D01*
G03X96017Y1320268I145J3499D01*
G03X96158Y1320271I-4J3502D01*
G01X115876D01*
G03X116017Y1320268I145J3499D01*
G03X116158Y1320271I-4J3502D01*
G01X135876D01*
G03X136017Y1320268I145J3499D01*
G03X136158Y1320271I-4J3502D01*
G01X155876D01*
G03X156017Y1320268I145J3499D01*
G03X156158Y1320271I-4J3502D01*
G01X175876D01*
G03X176017Y1320268I145J3499D01*
G03X176158Y1320271I-4J3502D01*
G01X176162D01*
G37*
G36*
G01X15748Y1324772D02*
X187795D01*
G02X201543Y1311024I0J-13748D01*
G01Y15748D01*
G02X187795Y2000I-13748J0D01*
G01X145474D01*
X140740Y6734D01*
Y42300D01*
G03X140815Y43307I-6723J1007D01*
G03X134016Y50106I-6799J0D01*
G03X134000I-8J-6799D01*
G01Y52030D01*
G02X142739Y43307I16J-8723D01*
G01Y7562D01*
X146302Y3999D01*
X187795D01*
G03X199544Y15748I0J11749D01*
G01Y1311024D01*
G03X187795Y1322773I-11749J0D01*
G01X15748D01*
G03X3999Y1311024I0J-11749D01*
G01Y15748D01*
G03X15748Y3999I11749J0D01*
G01X57241D01*
X60804Y7562D01*
Y43307D01*
G02X69500Y52030I8723J0D01*
G01Y50300D01*
X69306Y50106D01*
G03X62725Y43307I222J-6799D01*
G03X62803Y42280I6803J0D01*
G01Y6734D01*
X58069Y2000D01*
X15748D01*
G02X2000Y15748I0J13748D01*
G01Y1311024D01*
G02X15748Y1324772I13748J0D01*
G37*
%LPC*%
G75*
G36*
G01X102430Y59903D02*
G02X103385Y57500I-2546J-2403D01*
G02X96381I-3502J0D01*
G02X96501Y58407I3502J-2D01*
G03X96453Y58597I-193J52D01*
G02X95498Y61000I2546J2403D01*
G02X102502I3502J0D01*
G02X102382Y60093I-3502J2D01*
G03X102430Y59903I193J-52D01*
G37*
G36*
G01X114617Y78902D02*
G02X115918Y79152I1299J-3252D01*
G02Y72148I0J-3502D01*
G02X113985Y72730I0J3501D01*
G03X113801Y72748I-109J-167D01*
G02X112500Y72498I-1299J3252D01*
G02Y79502I0J3502D01*
G02X114433Y78920I0J-3501D01*
G03X114617Y78902I109J167D01*
G37*
G36*
G01X66699Y73053D02*
X66739Y73457D01*
X66707Y73543D01*
X66674Y73575D01*
G02X65598Y76100I2425J2525D01*
G02X69100Y79602I3502J0D01*
G02X71220Y78887I0J-3502D01*
G01X71259Y78858D01*
X71354Y78841D01*
X71759Y78968D01*
X71827Y79035D01*
X71842Y79082D01*
G02X75173Y81502I3331J-1082D01*
G02X78675Y78000I0J-3502D01*
G02X78659Y77664I-3502J-2D01*
G01X78654Y77611D01*
X78695Y77517D01*
X79053Y77248D01*
X79155Y77234D01*
X79205Y77254D01*
G02X80500Y77502I1294J-3254D01*
G02X76998Y74000I0J-3502D01*
G02X77014Y74336I3502J2D01*
G01X77019Y74389D01*
X76978Y74483D01*
X76620Y74752D01*
X76518Y74766D01*
X76468Y74746D01*
G02X75173Y74498I-1294J3254D01*
G02X73053Y75213I0J3502D01*
G01X73014Y75242D01*
X72919Y75259D01*
X72514Y75132D01*
X72446Y75065D01*
X72431Y75018D01*
G02X70988Y73150I-3331J1082D01*
G01X70949Y73126D01*
X70901Y73047D01*
X70861Y72643D01*
X70893Y72557D01*
X70926Y72525D01*
G02X72002Y70000I-2425J-2525D01*
G02X70613Y67207I-3503J0D01*
G01X70576Y67179D01*
X70534Y67097D01*
X70529Y66688D01*
X70568Y66605D01*
X70604Y66576D01*
G02X71918Y63842I-2187J-2734D01*
G02X64914I-3502J0D01*
G02X66303Y66635I3503J0D01*
G01X66340Y66663D01*
X66382Y66745D01*
X66387Y67154D01*
X66348Y67237D01*
X66312Y67266D01*
G02X64998Y70000I2187J2734D01*
G02X66612Y72950I3503J0D01*
G01X66651Y72974D01*
X66699Y73053D01*
G37*
G36*
G01X139853Y77378D02*
X139901Y77725D01*
X139884Y77797D01*
X139861Y77829D01*
G02X139225Y79842I2866J2013D01*
G02X146229I3502J0D01*
G02X144940Y77128I-3502J0D01*
G01X144910Y77104D01*
X144874Y77039D01*
X144826Y76692D01*
X144843Y76620D01*
X144866Y76588D01*
G02X145502Y74575I-2866J-2013D01*
G02X138498I-3502J0D01*
G02X139787Y77289I3502J0D01*
G01X139817Y77313D01*
X139853Y77378D01*
G37*
G36*
G01X63475Y81499D02*
G02X63977Y79692I-3001J-1807D01*
G02X56973I-3502J0D01*
G02X57972Y82141I3501J0D01*
G03X58000Y82385I-143J140D01*
G02X57498Y84192I3001J1807D01*
G02X64502I3502J0D01*
G02X63503Y81743I-3501J0D01*
G03X63475Y81499I143J-140D01*
G37*
G36*
G01X61618Y101039D02*
X61872Y101336D01*
X61896Y101420D01*
X61889Y101463D01*
G02X61848Y102000I3461J534D01*
G02X68852I3502J0D01*
G02X65355Y98498I-3502J0D01*
G01X65311D01*
X65232Y98461D01*
X64978Y98164D01*
X64954Y98080D01*
X64961Y98037D01*
G02X65002Y97500I-3461J-534D01*
G02X64830Y96416I-3502J0D01*
G01X64818Y96378D01*
X64824Y96299D01*
X64990Y95975D01*
X65051Y95924D01*
X65089Y95911D01*
G02X67527Y92575I-1063J-3336D01*
G02X60523I-3502J0D01*
G02X60695Y93659I3502J0D01*
G01X60707Y93697D01*
X60701Y93776D01*
X60535Y94100D01*
X60474Y94151D01*
X60436Y94164D01*
G02X57998Y97500I1063J3336D01*
G02X61495Y101002I3502J0D01*
G01X61539D01*
X61618Y101039D01*
G37*
G36*
G01X138607Y97977D02*
G02X138498Y98842I3393J867D01*
G02X139483Y101276I3502J-1D01*
G03X139510Y101520I-144J139D01*
G02X138998Y103342I2990J1823D01*
G02X146002I3502J0D01*
G02X145017Y100908I-3502J1D01*
G03X144990Y100664I144J-139D01*
G02X145502Y98842I-2990J-1823D01*
G02X144942Y96942I-3503J0D01*
G03X144981Y96680I168J-109D01*
G02X146229Y94000I-2254J-2680D01*
G02X142727Y90498I-3502J0D01*
G02X140799Y91077I1J3502D01*
G03X140578I-111J-167D01*
G02X138650Y90498I-1929J2923D01*
G02X135734Y92061I0J3502D01*
G01X135707Y92102D01*
X135624Y92148D01*
X135204Y92167D01*
X135118Y92127D01*
X135088Y92089D01*
G02X132350Y90771I-2738J2185D01*
G02X128848Y94273I0J3502D01*
G02X129728Y96594I3501J0D01*
G03X129736Y96850I-150J133D01*
G02X128998Y99000I2763J2150D01*
G02X136002I3502J0D01*
G02X135122Y96679I-3501J0D01*
G03X135114Y96423I150J-133D01*
G02X135266Y96212I-2763J-2151D01*
G01X135293Y96171D01*
X135376Y96125D01*
X135796Y96106D01*
X135882Y96146D01*
X135912Y96184D01*
G02X138263Y97481I2738J-2184D01*
G01X138307Y97485D01*
X138380Y97529D01*
X138602Y97850D01*
X138617Y97934D01*
X138607Y97977D01*
G37*
G36*
G01X90505Y103320D02*
X90884Y103564D01*
X90932Y103657D01*
X90930Y103710D01*
G02X90928Y103830I3500J118D01*
G02X94430Y100328I3502J0D01*
G02X92879Y100690I0J3502D01*
G01X92831Y100714D01*
X92727Y100708D01*
X92348Y100464D01*
X92300Y100371D01*
X92302Y100318D01*
G02X92304Y100198I-3500J-118D01*
G02X91886Y98539I-3501J0D01*
G01X91865Y98499D01*
X91860Y98411D01*
X92009Y98042D01*
X92075Y97982D01*
X92117Y97968D01*
G02X94561Y94630I-1058J-3338D01*
G02X91059Y91128I-3502J0D01*
G02X89892Y91328I0J3502D01*
G01X89852Y91342D01*
X89770Y91336D01*
X89436Y91163D01*
X89384Y91099D01*
X89373Y91059D01*
G02X86000Y88498I-3373J941D01*
G02Y95502I0J3502D01*
G02X87167Y95302I0J-3502D01*
G01X87207Y95288D01*
X87289Y95294D01*
X87623Y95467D01*
X87675Y95531D01*
X87686Y95571D01*
G02X87975Y96289I3373J-941D01*
G01X87996Y96329D01*
X88001Y96417D01*
X87852Y96786D01*
X87786Y96846D01*
X87744Y96860D01*
G02X85300Y100198I1058J3338D01*
G02X88802Y103700I3502J0D01*
G02X90353Y103338I0J-3502D01*
G01X90401Y103314D01*
X90505Y103320D01*
G37*
G36*
G01X22735Y99858D02*
Y100220D01*
X22706Y100292D01*
X22677Y100320D01*
G02X21176Y103976I3702J3656D01*
G02X26378Y109178I5202J0D01*
G02X30034Y107677I0J-5203D01*
G01X30062Y107648D01*
X30134Y107619D01*
X30496D01*
X30568Y107648D01*
X30596Y107677D01*
G02X34252Y109178I3656J-3702D01*
G02X39454Y103976I0J-5202D01*
G02X37953Y100320I-5203J0D01*
G01X37924Y100292D01*
X37895Y100220D01*
Y99858D01*
X37924Y99786D01*
X37953Y99758D01*
G02Y92446I-3702J-3656D01*
G01X37924Y92418D01*
X37895Y92346D01*
Y91984D01*
X37924Y91912D01*
X37953Y91884D01*
G02Y84572I-3702J-3656D01*
G01X37924Y84544D01*
X37895Y84472D01*
Y84110D01*
X37924Y84038D01*
X37953Y84010D01*
G02Y76698I-3702J-3656D01*
G01X37924Y76670D01*
X37895Y76598D01*
Y76236D01*
X37924Y76164D01*
X37953Y76136D01*
G02Y68824I-3702J-3656D01*
G01X37924Y68796D01*
X37895Y68724D01*
Y68362D01*
X37924Y68290D01*
X37953Y68262D01*
G02X39454Y64606I-3702J-3656D01*
G02X37953Y60950I-5203J0D01*
G01X37924Y60922D01*
X37895Y60850D01*
Y60488D01*
X37924Y60416D01*
X37953Y60388D01*
G02X39454Y56732I-3702J-3656D01*
G02X37953Y53076I-5203J0D01*
G01X37924Y53048D01*
X37895Y52976D01*
Y52614D01*
X37924Y52542D01*
X37953Y52514D01*
G02X39454Y48858I-3702J-3656D01*
G02X35216Y43746I-5202J0D01*
G01X35171Y43738D01*
X35099Y43686D01*
X34907Y43336D01*
X34901Y43247D01*
X34918Y43205D01*
G02X25712I-4603J-1827D01*
G01X25729Y43247D01*
X25723Y43336D01*
X25531Y43686D01*
X25459Y43738D01*
X25414Y43746D01*
G02X21176Y48858I964J5112D01*
G02X22677Y52514I5203J0D01*
G01X22706Y52542D01*
X22735Y52614D01*
Y52976D01*
X22706Y53048D01*
X22677Y53076D01*
G02X21176Y56732I3702J3656D01*
G02X22677Y60388I5203J0D01*
G01X22706Y60416D01*
X22735Y60488D01*
Y60850D01*
X22706Y60922D01*
X22677Y60950D01*
G02X21176Y64606I3702J3656D01*
G02X22677Y68262I5203J0D01*
G01X22706Y68290D01*
X22735Y68362D01*
Y68724D01*
X22706Y68796D01*
X22677Y68824D01*
G02Y76136I3702J3656D01*
G01X22706Y76164D01*
X22735Y76236D01*
Y76598D01*
X22706Y76670D01*
X22677Y76698D01*
G02Y84010I3702J3656D01*
G01X22706Y84038D01*
X22735Y84110D01*
Y84472D01*
X22706Y84544D01*
X22677Y84572D01*
G02Y91884I3702J3656D01*
G01X22706Y91912D01*
X22735Y91984D01*
Y92346D01*
X22706Y92418D01*
X22677Y92446D01*
G02Y99758I3702J3656D01*
G01X22706Y99786D01*
X22735Y99858D01*
G37*
G36*
G01X168444Y109148D02*
X168636Y109498D01*
X168642Y109587D01*
X168625Y109629D01*
G02X177831I4603J1827D01*
G01X177814Y109587D01*
X177820Y109498D01*
X178012Y109148D01*
X178084Y109096D01*
X178129Y109088D01*
G02X182367Y103976I-964J-5112D01*
G02X180866Y100320I-5203J0D01*
G01X180837Y100292D01*
X180808Y100220D01*
Y99858D01*
X180837Y99786D01*
X180866Y99758D01*
G02Y92446I-3702J-3656D01*
G01X180837Y92418D01*
X180808Y92346D01*
Y91984D01*
X180837Y91912D01*
X180866Y91884D01*
G02Y84572I-3702J-3656D01*
G01X180837Y84544D01*
X180808Y84472D01*
Y84110D01*
X180837Y84038D01*
X180866Y84010D01*
G02Y76698I-3702J-3656D01*
G01X180837Y76670D01*
X180808Y76598D01*
Y76236D01*
X180837Y76164D01*
X180866Y76136D01*
G02Y68824I-3702J-3656D01*
G01X180837Y68796D01*
X180808Y68724D01*
Y68362D01*
X180837Y68290D01*
X180866Y68262D01*
G02X182367Y64606I-3702J-3656D01*
G02X180866Y60950I-5203J0D01*
G01X180837Y60922D01*
X180808Y60850D01*
Y60488D01*
X180837Y60416D01*
X180866Y60388D01*
G02Y53076I-3702J-3656D01*
G01X180837Y53048D01*
X180808Y52976D01*
Y52614D01*
X180837Y52542D01*
X180866Y52514D01*
G02X182367Y48858I-3702J-3656D01*
G02X177165Y43656I-5202J0D01*
G02X173509Y45157I0J5203D01*
G01X173481Y45186D01*
X173409Y45215D01*
X173047D01*
X172975Y45186D01*
X172947Y45157D01*
G02X169291Y43656I-3656J3702D01*
G02X164089Y48858I0J5202D01*
G02X165590Y52514I5203J0D01*
G01X165619Y52542D01*
X165648Y52614D01*
Y52976D01*
X165619Y53048D01*
X165590Y53076D01*
G02Y60388I3702J3656D01*
G01X165619Y60416D01*
X165648Y60488D01*
Y60850D01*
X165619Y60922D01*
X165590Y60950D01*
G02X164089Y64606I3702J3656D01*
G02X165590Y68262I5203J0D01*
G01X165619Y68290D01*
X165648Y68362D01*
Y68724D01*
X165619Y68796D01*
X165590Y68824D01*
G02Y76136I3702J3656D01*
G01X165619Y76164D01*
X165648Y76236D01*
Y76598D01*
X165619Y76670D01*
X165590Y76698D01*
G02Y84010I3702J3656D01*
G01X165619Y84038D01*
X165648Y84110D01*
Y84472D01*
X165619Y84544D01*
X165590Y84572D01*
G02Y91884I3702J3656D01*
G01X165619Y91912D01*
X165648Y91984D01*
Y92346D01*
X165619Y92418D01*
X165590Y92446D01*
G02Y99758I3702J3656D01*
G01X165619Y99786D01*
X165648Y99858D01*
Y100220D01*
X165619Y100292D01*
X165590Y100320D01*
G02X164089Y103976I3702J3656D01*
G02X168327Y109088I5202J0D01*
G01X168372Y109096D01*
X168444Y109148D01*
G37*
G36*
G01X134096Y111362D02*
X134291Y111728D01*
X134293Y111821D01*
X134273Y111864D01*
G02X133947Y113340I3176J1476D01*
G02X137449Y116842I3502J0D01*
G02X137903Y116812I-3J-3502D01*
G03X138112Y116931I25J198D01*
G02X141327Y119044I3215J-1389D01*
G02Y112040I0J-3502D01*
G02X140873Y112070I3J3502D01*
G03X140664Y111951I-25J-198D01*
G02X138000Y109882I-3215J1389D01*
G01X137953Y109874D01*
X137878Y109820D01*
X137683Y109454D01*
X137681Y109361D01*
X137701Y109318D01*
G02X138027Y107842I-3176J-1476D01*
G02X131023I-3502J0D01*
G02X133974Y111300I3502J0D01*
G01X134021Y111308D01*
X134096Y111362D01*
G37*
G36*
G01X122088Y118790D02*
G02X125500Y121502I3412J-790D01*
G02X129002Y118000I0J-3502D01*
G02X127020Y114845I-3502J0D01*
G03X126912Y114710I87J-180D01*
G02X123500Y111998I-3412J790D01*
G02X119998Y115500I0J3502D01*
G02X121980Y118655I3502J0D01*
G03X122088Y118790I-87J180D01*
G37*
G36*
G01X72172Y133472D02*
X72469Y133703D01*
X72509Y133775D01*
X72512Y133817D01*
G02X76000Y137002I3488J-317D01*
G02X79502Y133500I0J-3502D01*
G02X78810Y131409I-3502J-1D01*
G03X78783Y131220I160J-119D01*
G02X79002Y130000I-3283J-1219D01*
G02X75500Y126498I-3502J0D01*
G02X73608Y127053I0J3502D01*
G03X73392I-108J-168D01*
G02X71500Y126498I-1892J2947D01*
G02Y133502I0J3502D01*
G02X72051Y133458I-2J-3502D01*
G01X72092Y133452D01*
X72172Y133472D01*
G37*
G36*
G01X145280Y147967D02*
G02X145074Y149149I3296J1183D01*
G02X148576Y152651I3502J0D01*
G02X149995Y152351I1J-3502D01*
G03X150157I81J182D01*
G02X151576Y152651I1418J-3202D01*
G02X152995Y152351I1J-3502D01*
G03X153157I81J182D01*
G02X154576Y152651I1418J-3202D01*
G02X158078Y149149I0J-3502D01*
G02X157872Y147967I-3502J1D01*
G03Y147831I189J-68D01*
G02X158078Y146649I-3296J-1183D01*
G02X154576Y143147I-3502J0D01*
G02X153157Y143447I-1J3502D01*
G03X152995I-81J-182D01*
G02X151576Y143147I-1418J3202D01*
G02X150157Y143447I-1J3502D01*
G03X149995I-81J-182D01*
G02X148576Y143147I-1418J3202D01*
G02X145074Y146649I0J3502D01*
G02X145280Y147831I3502J-1D01*
G03Y147967I-189J68D01*
G37*
G36*
G01X41157Y148340D02*
G02X40897Y149664I3241J1324D01*
G02X41103Y150846I3502J-1D01*
G03Y150982I-189J68D01*
G02X40897Y152164I3296J1183D01*
G02X44399Y155666I3502J0D01*
G02X45818Y155366I1J-3502D01*
G03X45980I81J182D01*
G02X47399Y155666I1418J-3202D01*
G02X50901Y152164I0J-3502D01*
G02X50695Y150982I-3502J1D01*
G03Y150846I189J-68D01*
G02X50901Y149664I-3296J-1183D01*
G02X50641Y148340I-3501J0D01*
G03Y148188I185J-76D01*
G02X50901Y146864I-3241J-1324D01*
G02X47399Y143362I-3502J0D01*
G02X45980Y143662I-1J3502D01*
G03X45818I-81J-182D01*
G02X44399Y143362I-1418J3202D01*
G02X40897Y146864I0J3502D01*
G02X41157Y148188I3501J0D01*
G03Y148340I-185J76D01*
G37*
G36*
G01X186462Y169424D02*
G02X186162Y170843I3202J1418D01*
G02X186462Y172262I3502J1D01*
G03Y172424I-182J81D01*
G02X186162Y173843I3202J1418D01*
G02X189664Y177345I3502J0D01*
G02X190846Y177139I-1J-3502D01*
G03X190982I68J189D01*
G02X192164Y177345I1183J-3296D01*
G02X195666Y173843I0J-3502D01*
G02X195366Y172424I-3502J-1D01*
G03Y172262I182J-81D01*
G02X195666Y170843I-3202J-1418D01*
G02X195366Y169424I-3502J-1D01*
G03Y169262I182J-81D01*
G02X195666Y167843I-3202J-1418D01*
G02X195366Y166424I-3502J-1D01*
G03Y166262I182J-81D01*
G02X195666Y164843I-3202J-1418D01*
G02X192164Y161341I-3502J0D01*
G02X190982Y161547I1J3502D01*
G03X190846I-68J-189D01*
G02X189664Y161341I-1183J3296D01*
G02X186162Y164843I0J3502D01*
G02X186462Y166262I3502J1D01*
G03Y166424I-182J81D01*
G02X186162Y167843I3202J1418D01*
G02X186462Y169262I3502J1D01*
G03Y169424I-182J81D01*
G37*
G36*
G01X45906Y168062D02*
G02X44487Y167762I-1418J3202D01*
G02X40985Y171264I0J3502D01*
G02X41285Y172683I3502J1D01*
G03Y172845I-182J81D01*
G02X40985Y174264I3202J1418D01*
G02X44487Y177766I3502J0D01*
G02X45906Y177466I1J-3502D01*
G03X46068I81J182D01*
G02X47487Y177766I1418J-3202D01*
G02X50989Y174264I0J-3502D01*
G02X50689Y172845I-3502J-1D01*
G03Y172683I182J-81D01*
G02X50989Y171264I-3202J-1418D01*
G02X47487Y167762I-3502J0D01*
G02X46068Y168062I-1J3502D01*
G03X45906I-81J-182D01*
G37*
G36*
G01X146462Y170024D02*
G02X146162Y171443I3202J1418D01*
G02X146462Y172862I3502J1D01*
G03Y173024I-182J81D01*
G02X146162Y174443I3202J1418D01*
G02X153166I3502J0D01*
G02X152866Y173024I-3502J-1D01*
G03Y172862I182J-81D01*
G02X153166Y171443I-3202J-1418D01*
G02X152866Y170024I-3502J-1D01*
G03Y169862I182J-81D01*
G02X153166Y168443I-3202J-1418D01*
G02X152866Y167024I-3502J-1D01*
G03Y166862I182J-81D01*
G02X153166Y165443I-3202J-1418D01*
G02X146162I-3502J0D01*
G02X146462Y166862I3502J1D01*
G03Y167024I-182J81D01*
G02X146162Y168443I3202J1418D01*
G02X146462Y169862I3502J1D01*
G03Y170024I-182J81D01*
G37*
G36*
G01X9987Y177701D02*
G02X9578Y179343I3093J1642D01*
G02X9878Y180762I3502J1D01*
G03Y180924I-182J81D01*
G02X9578Y182343I3202J1418D01*
G02X16582I3502J0D01*
G02X16282Y180924I-3502J-1D01*
G03Y180762I182J-81D01*
G02X16582Y179343I-3202J-1418D01*
G02X15857Y177210I-3502J1D01*
G01X15834Y177179D01*
X15813Y177104D01*
X15854Y176749D01*
X15892Y176681D01*
X15922Y176656D01*
G02X17210Y173943I-2213J-2713D01*
G02X16910Y172524I-3502J-1D01*
G03Y172362I182J-81D01*
G02X17210Y170943I-3202J-1418D01*
G02X13708Y167441I-3502J0D01*
G02X12526Y167647I1J3502D01*
G03X12390I-68J-189D01*
G02X11208Y167441I-1183J3296D01*
G02X7706Y170943I0J3502D01*
G02X8006Y172362I3502J1D01*
G03Y172524I-182J81D01*
G02X7706Y173943I3202J1418D01*
G02X9795Y177147I3502J0D01*
G01X9834Y177164D01*
X9889Y177225D01*
X10013Y177581D01*
X10007Y177664D01*
X9987Y177701D01*
G37*
G36*
G01X190166Y187462D02*
G02X190466Y186043I-3202J-1418D01*
G02X183462I-3502J0D01*
G02X183762Y187462I3502J1D01*
G03Y187624I-182J81D01*
G02X183462Y189043I3202J1418D01*
G02X190466I3502J0D01*
G02X190166Y187624I-3502J-1D01*
G03Y187462I182J-81D01*
G37*
G36*
G01X32716Y196218D02*
G02X30978Y199243I1764J3025D01*
G02X31278Y200662I3502J1D01*
G03Y200824I-182J81D01*
G02X30978Y202243I3202J1418D01*
G02X37982I3502J0D01*
G02X37682Y200824I-3502J-1D01*
G03Y200662I182J-81D01*
G02X37982Y199243I-3202J-1418D01*
G02X36302Y196252I-3503J0D01*
G01X36256Y196224D01*
X36205Y196133D01*
X36210Y195682D01*
X36262Y195592D01*
X36308Y195565D01*
G02X38046Y192540I-1764J-3025D01*
G02X37746Y191121I-3502J-1D01*
G03Y190959I182J-81D01*
G02X38046Y189540I-3202J-1418D01*
G02X36107Y186406I-3502J0D01*
G01X36056Y186381D01*
X35998Y186288D01*
X35986Y185822D01*
X36041Y185727D01*
X36090Y185699D01*
G02X37882Y182643I-1710J-3056D01*
G02X37582Y181224I-3502J-1D01*
G03Y181062I182J-81D01*
G02X37882Y179643I-3202J-1418D01*
G02X30878I-3502J0D01*
G02X31178Y181062I3502J1D01*
G03Y181224I-182J81D01*
G02X30878Y182643I3202J1418D01*
G02X32817Y185777I3502J0D01*
G01X32868Y185802D01*
X32926Y185895D01*
X32938Y186361D01*
X32883Y186456D01*
X32834Y186484D01*
G02X31042Y189540I1710J3056D01*
G02X31342Y190959I3502J1D01*
G03Y191121I-182J81D01*
G02X31042Y192540I3202J1418D01*
G02X32722Y195531I3503J0D01*
G01X32768Y195559D01*
X32819Y195650D01*
X32814Y196101D01*
X32762Y196191D01*
X32716Y196218D01*
G37*
G36*
G01X11832Y205155D02*
G02X11289Y207028I2959J1873D01*
G02X11589Y208447I3502J1D01*
G03Y208609I-182J81D01*
G02X11289Y210028I3202J1418D01*
G02X18293I3502J0D01*
G02X17993Y208609I-3502J-1D01*
G03Y208447I182J-81D01*
G02X18293Y207028I-3202J-1418D01*
G02X16663Y204068I-3503J0D01*
G01X16629Y204047D01*
X16583Y203982D01*
X16504Y203628D01*
X16518Y203550D01*
X16539Y203516D01*
G02X17082Y201643I-2959J-1873D01*
G02X16782Y200224I-3502J-1D01*
G03Y200062I182J-81D01*
G02X17082Y198643I-3202J-1418D01*
G02X15679Y195840I-3502J0D01*
G01X15644Y195814D01*
X15604Y195740D01*
X15571Y195356D01*
X15598Y195277D01*
X15628Y195245D01*
G02X16582Y192843I-2547J-2402D01*
G02X16282Y191424I-3502J-1D01*
G03Y191262I182J-81D01*
G02X16582Y189843I-3202J-1418D01*
G02X9578I-3502J0D01*
G02X9878Y191262I3502J1D01*
G03Y191424I-182J81D01*
G02X9578Y192843I3202J1418D01*
G02X10981Y195646I3502J0D01*
G01X11016Y195672D01*
X11056Y195746D01*
X11089Y196130D01*
X11062Y196209D01*
X11032Y196241D01*
G02X10078Y198643I2547J2402D01*
G02X10378Y200062I3502J1D01*
G03Y200224I-182J81D01*
G02X10078Y201643I3202J1418D01*
G02X11708Y204603I3503J0D01*
G01X11742Y204624D01*
X11788Y204689D01*
X11867Y205043D01*
X11853Y205121D01*
X11832Y205155D01*
G37*
G36*
G01X32393Y208847D02*
G02X32693Y207428I-3202J-1418D01*
G02X25689I-3502J0D01*
G02X25989Y208847I3502J1D01*
G03Y209009I-182J81D01*
G02X25689Y210428I3202J1418D01*
G02X32693I3502J0D01*
G02X32393Y209009I-3502J-1D01*
G03Y208847I182J-81D01*
G37*
G36*
G01X183244Y210742D02*
G02X180080Y214228I338J3486D01*
G02X180380Y215647I3502J1D01*
G03Y215809I-182J81D01*
G02X180080Y217228I3202J1418D01*
G02X187084I3502J0D01*
G02X186784Y215809I-3502J-1D01*
G03Y215647I182J-81D01*
G02X187084Y214228I-3202J-1418D01*
G02X186776Y212791I-3502J-1D01*
G01X186756Y212747D01*
X186761Y212651D01*
X186972Y212285D01*
X187053Y212233D01*
X187102Y212229D01*
G02X190266Y208743I-338J-3486D01*
G02X189966Y207324I-3502J-1D01*
G03Y207162I182J-81D01*
G02X190266Y205743I-3202J-1418D01*
G02X188978Y203029I-3503J0D01*
G01X188941Y203000D01*
X188903Y202915D01*
X188916Y202503D01*
X188960Y202421D01*
X188998Y202394D01*
G02X190466Y199543I-2034J-2851D01*
G02X190166Y198124I-3502J-1D01*
G03Y197962I182J-81D01*
G02X190466Y196543I-3202J-1418D01*
G02X183462I-3502J0D01*
G02X183762Y197962I3502J1D01*
G03Y198124I-182J81D01*
G02X183462Y199543I3202J1418D01*
G02X184750Y202257I3503J0D01*
G01X184787Y202286D01*
X184825Y202371D01*
X184812Y202783D01*
X184768Y202865D01*
X184730Y202892D01*
G02X183262Y205743I2034J2851D01*
G02X183562Y207162I3502J1D01*
G03Y207324I-182J81D01*
G02X183262Y208743I3202J1418D01*
G02X183570Y210180I3502J1D01*
G01X183590Y210224D01*
X183585Y210320D01*
X183374Y210686D01*
X183293Y210738D01*
X183244Y210742D01*
G37*
G36*
G01X100115Y139484D02*
G02X84052Y157125I1656J17641D01*
G01Y204370D01*
G02X119490I17719J0D01*
G01Y157125D01*
G02X105511Y139805I-17719J0D01*
G01X105455Y139793D01*
X105374Y139715D01*
X105254Y139261D01*
X105287Y139153D01*
X105329Y139115D01*
G02X106502Y136500I-2328J-2615D01*
G02X99498I-3502J0D01*
G02X100377Y138820I3501J0D01*
G01X100415Y138863D01*
X100434Y138974D01*
X100261Y139411D01*
X100171Y139478D01*
X100115Y139484D01*
G37*
G36*
G01X11291Y230762D02*
G02X11085Y231944I3296J1183D01*
G02X14587Y235446I3502J0D01*
G02X15769Y235240I-1J-3502D01*
G03X15905I68J189D01*
G02X17087Y235446I1183J-3296D01*
G02X18307Y235227I1J-3502D01*
G03X18447I70J187D01*
G02X19667Y235446I1219J-3283D01*
G02X23169Y231944I0J-3502D01*
G02X22963Y230762I-3502J1D01*
G03Y230626I189J-68D01*
G02X23169Y229444I-3296J-1183D01*
G02X19667Y225942I-3502J0D01*
G02X18466Y226155I2J3502D01*
G03X18328I-69J-188D01*
G02X17127Y225942I-1203J3289D01*
G02X15926Y226155I2J3502D01*
G03X15788I-69J-188D01*
G02X14587Y225942I-1203J3289D01*
G02X11085Y229444I0J3502D01*
G02X11291Y230626I3502J-1D01*
G03Y230762I-189J68D01*
G37*
G36*
G01X134921Y230709D02*
G02X134696Y231944I3277J1235D01*
G02X138198Y235446I3502J0D01*
G02X139418Y235227I1J-3502D01*
G03X139558I70J187D01*
G02X140778Y235446I1219J-3283D01*
G02X141998Y235227I1J-3502D01*
G03X142138I70J187D01*
G02X143358Y235446I1219J-3283D01*
G02X146860Y231944I0J-3502D01*
G02X146654Y230762I-3502J1D01*
G03Y230626I189J-68D01*
G02X146860Y229444I-3296J-1183D01*
G02X143358Y225942I-3502J0D01*
G02X142157Y226155I2J3502D01*
G03X142019I-69J-188D01*
G02X140818Y225942I-1203J3289D01*
G02X139598Y226161I-1J3502D01*
G03X139458I-70J-187D01*
G02X138238Y225942I-1219J3283D01*
G02X134736Y229444I0J3502D01*
G02X134923Y230574I3502J1D01*
G03X134921Y230709I-189J65D01*
G37*
G36*
G01X15907Y251108D02*
G02X17782Y251652I1875J-2959D01*
G02X20960Y249622I0J-3503D01*
G03X21197Y249514I181J84D01*
G02X22074Y249651I975J-3364D01*
G03X22256Y249782I-6J200D01*
G02X25545Y252080I3289J-1205D01*
G02X28486Y250479I0J-3502D01*
G03X28694Y250392I168J109D01*
G02X29390Y250462I697J-3432D01*
G02Y243458I0J-3502D01*
G02X29211Y243463I8J3502D01*
G03X29030Y243367I-10J-200D01*
G02X26040Y241688I-2990J1823D01*
G02X23499Y242780I0J3502D01*
G03X23290Y242832I-145J-138D01*
G02X22170Y242648I-1120J3317D01*
G02X18992Y244678I0J3503D01*
G03X18755Y244786I-181J-84D01*
G02X17782Y244648I-973J3364D01*
G02X16827Y244781I1J3502D01*
G03X16666Y244757I-54J-193D01*
G02X14791Y244213I-1875J2959D01*
G02Y251217I0J3502D01*
G02X15746Y251084I-1J-3502D01*
G03X15907Y251108I54J193D01*
G37*
G36*
G01X138501Y245380D02*
X138398Y245437D01*
G03X138258Y245457I-96J-175D01*
G02X137495Y245373I-762J3418D01*
G02Y252377I0J3502D01*
G02X140793Y250054I0J-3503D01*
G03X140884Y249946I188J66D01*
G01X140987Y249889D01*
G03X141127Y249869I96J175D01*
G02X141890Y249953I762J-3418D01*
G02Y242949I0J-3502D01*
G02X138592Y245272I0J3503D01*
G03X138501Y245380I-188J-66D01*
G37*
G36*
G01X153912Y246211D02*
G02X150500Y243498I-3412J789D01*
G02X146998Y247000I0J3502D01*
G01Y247023D01*
G03X146917Y247185I-200J1D01*
G02X145498Y250000I2083J2815D01*
G02X149000Y253502I3502J0D01*
G02X151090Y252810I0J-3502D01*
G03X151279Y252783I119J161D01*
G02X152500Y253003I1222J-3282D01*
G02X156002Y249501I0J-3502D01*
G02X154020Y246346I-3502J0D01*
G03X153912Y246211I87J-180D01*
G37*
G36*
G01X158553Y248275D02*
X158672Y248701D01*
X158648Y248801D01*
X158613Y248840D01*
G02X157698Y251200I2586J2360D01*
G02X164702I3502J0D01*
G02X163697Y248745I-3501J0D01*
G01X163660Y248707D01*
X163633Y248606D01*
X163744Y248172D01*
X163817Y248097D01*
X163867Y248081D01*
G02X164277Y247930I-1003J-3355D01*
G03X164439I81J182D01*
G02X165858Y248230I1418J-3202D01*
G02Y241226I0J-3502D01*
G02X164439Y241526I-1J3502D01*
G03X164277I-81J-182D01*
G02X162858Y241226I-1418J3202D01*
G02X161144Y241674I0J3503D01*
G03X160959Y241679I-97J-175D01*
G02X159430Y241328I-1528J3151D01*
G02X155928Y244830I0J3502D01*
G02X158432Y248187I3502J0D01*
G01X158481Y248201D01*
X158553Y248275D01*
G37*
G36*
G01X35764Y245755D02*
X35710Y245860D01*
G03X35605Y245955I-178J-91D01*
G02X33378Y249217I1276J3262D01*
G02X36880Y252719I3502J0D01*
G02X38488Y252328I0J-3502D01*
G01X38527Y252308D01*
X38610Y252303D01*
X38969Y252439D01*
X39029Y252498D01*
X39045Y252538D01*
G02X42309Y254772I3264J-1267D01*
G02X45811Y251270I0J-3502D01*
G02X44153Y248293I-3502J0D01*
G01X44109Y248266D01*
X44060Y248179D01*
X44050Y247740D01*
X44096Y247651D01*
X44139Y247622D01*
G02X45669Y244728I-1972J-2894D01*
G02X42167Y241226I-3502J0D01*
G02X40748Y241526I-1J3502D01*
G03X40586I-81J-182D01*
G02X39167Y241226I-1418J3202D01*
G02X35665Y244728I0J3502D01*
G02X35779Y245614I3502J0D01*
G03X35764Y245755I-194J51D01*
G37*
G36*
G01X179648Y259730D02*
G02X181067Y260030I1418J-3202D01*
G02X182486Y259730I1J-3502D01*
G03X182648I81J182D01*
G02X184067Y260030I1418J-3202D01*
G02X185486Y259730I1J-3502D01*
G03X185648I81J182D01*
G02X187067Y260030I1418J-3202D01*
G02X190569Y256528I0J-3502D01*
G02X190259Y255088I-3502J1D01*
G03X190254Y254937I183J-82D01*
G02X190469Y253728I-3287J-1208D01*
G02X186967Y250226I-3502J0D01*
G02X185548Y250526I-1J3502D01*
G03X185386I-81J-182D01*
G02X183967Y250226I-1418J3202D01*
G02X182548Y250526I-1J3502D01*
G03X182386I-81J-182D01*
G02X180967Y250226I-1418J3202D01*
G02X179548Y250526I-1J3502D01*
G03X179386I-81J-182D01*
G02X177967Y250226I-1418J3202D01*
G02X174465Y253728I0J3502D01*
G02X174775Y255168I3502J-1D01*
G03X174780Y255319I-183J82D01*
G02X174565Y256528I3287J1208D01*
G02X178067Y260030I3502J0D01*
G02X179486Y259730I1J-3502D01*
G03X179648I81J182D01*
G37*
G36*
G01X53748Y262430D02*
G02X55167Y262730I1418J-3202D01*
G02X56586Y262430I1J-3502D01*
G03X56748I81J182D01*
G02X58167Y262730I1418J-3202D01*
G02X59586Y262430I1J-3502D01*
G03X59748I81J182D01*
G02X61167Y262730I1418J-3202D01*
G02X64669Y259228I0J-3502D01*
G02X64389Y257856I-3501J0D01*
G03Y257700I184J-78D01*
G02X64669Y256328I-3221J-1372D01*
G02X61167Y252826I-3502J0D01*
G02X59748Y253126I-1J3502D01*
G03X59586I-81J-182D01*
G02X58167Y252826I-1418J3202D01*
G02X56748Y253126I-1J3502D01*
G03X56586I-81J-182D01*
G02X55167Y252826I-1418J3202D01*
G02X53748Y253126I-1J3502D01*
G03X53586I-81J-182D01*
G02X52167Y252826I-1418J3202D01*
G02X48665Y256328I0J3502D01*
G02X48945Y257700I3501J0D01*
G03Y257856I-184J78D01*
G02X48665Y259228I3221J1372D01*
G02X52167Y262730I3502J0D01*
G02X53586Y262430I1J-3502D01*
G03X53748I81J182D01*
G37*
G36*
G01X158170Y268525D02*
X158541Y268515D01*
X158616Y268545D01*
X158645Y268574D01*
G02X161105Y269583I2460J-2494D01*
G02X161585Y269550I0J-3502D01*
G03X161796Y269669I27J198D01*
G02X165014Y271789I3218J-1382D01*
G02Y264785I0J-3502D01*
G02X164534Y264818I0J3502D01*
G03X164323Y264699I-27J-198D01*
G02X161105Y262579I-3218J1382D01*
G02X158518Y263720I0J3503D01*
G01X158491Y263751D01*
X158417Y263784D01*
X158046Y263794D01*
X157971Y263764D01*
X157942Y263735D01*
G02X155482Y262726I-2460J2494D01*
G02Y269730I0J3502D01*
G02X158069Y268589I0J-3503D01*
G01X158096Y268558D01*
X158170Y268525D01*
G37*
G36*
G01X136386Y268549D02*
X136189Y268932D01*
X136108Y268989D01*
X136059Y268995D01*
G02X132980Y272471I423J3476D01*
G02X136482Y275973I3502J0D01*
G02X139937Y273043I0J-3502D01*
G01X139945Y272993D01*
X140005Y272915D01*
X140402Y272736D01*
X140500Y272742D01*
X140544Y272769D01*
G02X142400Y273302I1857J-2969D01*
G02X145254Y271830I0J-3503D01*
G03X145447Y271748I163J116D01*
G02X145982Y271789I534J-3461D01*
G02X149467Y268630I0J-3502D01*
G03X149543Y268492I199J20D01*
G02X150895Y265728I-2149J-2764D01*
G02X147393Y262226I-3502J0D01*
G02X146016Y262508I0J3503D01*
G03X145859I-79J-184D01*
G02X144482Y262226I-1377J3221D01*
G02X141650Y263668I0J3502D01*
G03X141527Y263746I-161J-118D01*
G01X141411Y263769D01*
G03X141267Y263744I-40J-196D01*
G02X139880Y263254I-1834J2983D01*
G01X139831Y263248D01*
X139751Y263192D01*
X139555Y262809D01*
X139556Y262712D01*
X139580Y262667D01*
G02X140002Y261000I-3080J-1667D01*
G02X132998I-3502J0D01*
G02X133038Y261525I3502J-3D01*
G01X133043Y261563D01*
X133027Y261636D01*
X132832Y261924D01*
X132770Y261966D01*
X132733Y261975D01*
G02X130027Y265385I796J3410D01*
G02X133529Y268887I3502J0D01*
G02X135690Y268141I0J-3503D01*
G01X135725Y268113D01*
X135813Y268093D01*
X136204Y268182D01*
X136275Y268238D01*
X136295Y268279D01*
G02X136361Y268406I3140J-1551D01*
G01X136385Y268450D01*
X136386Y268549D01*
G37*
G36*
G01X53940Y276052D02*
G02X53228Y278117I2790J2117D01*
G03X53170Y278255I-200J-3D01*
G02X52148Y280728I2481J2473D01*
G02X55650Y284230I3502J0D01*
G02X57027Y283948I0J-3503D01*
G03X57184I79J184D01*
G02X58561Y284230I1377J-3221D01*
G02X62063Y280728I0J-3502D01*
G02X60273Y277673I-3502J0D01*
G03X60174Y277535I98J-175D01*
G02X59397Y275899I-3444J633D01*
G03X59355Y275723I152J-129D01*
G01X59384Y275603D01*
G03X59502Y275466I194J48D01*
G02X59586Y275430I-1337J-3237D01*
G03X59748I81J182D01*
G02X61167Y275730I1418J-3202D01*
G02X62586Y275430I1J-3502D01*
G03X62748I81J182D01*
G02X63401Y275645I1416J-3203D01*
G03X63531Y275740I-43J196D01*
G02X66561Y277487I3030J-1754D01*
G02X70063Y273985I0J-3502D01*
G02X67327Y270568I-3502J0D01*
G03X67197Y270473I43J-196D01*
G02X64167Y268726I-3030J1754D01*
G02X62748Y269026I-1J3502D01*
G03X62586I-81J-182D01*
G02X61167Y268726I-1418J3202D01*
G02X59748Y269026I-1J3502D01*
G03X59586I-81J-182D01*
G02X58167Y268726I-1418J3202D01*
G02X56748Y269026I-1J3502D01*
G03X56586I-81J-182D01*
G02X55167Y268726I-1418J3202D01*
G02X51665Y272228I0J3502D01*
G02X53780Y275444I3503J0D01*
G01X53822Y275462D01*
X53882Y275531D01*
X53986Y275926D01*
X53968Y276016D01*
X53940Y276052D01*
G37*
G36*
G01X36974Y283444D02*
G02X40472Y286789I3498J-156D01*
G02X43974Y283287I0J-3502D01*
G02X41994Y280133I-3502J0D01*
G03X41881Y279962I87J-180D01*
G02X38383Y276617I-3498J156D01*
G02X34881Y280119I0J3502D01*
G02X36861Y283273I3502J0D01*
G03X36974Y283444I-87J180D01*
G37*
G36*
G01X146365Y281575D02*
X146515Y281908D01*
X146517Y281988D01*
X146502Y282025D01*
G02X146267Y283287I3267J1261D01*
G02X153271I3502J0D01*
G02X150999Y280008I-3502J0D01*
G01X150962Y279994D01*
X150904Y279940D01*
X150754Y279607D01*
X150752Y279527D01*
X150767Y279490D01*
G02X151002Y278228I-3267J-1261D01*
G02X143998I-3502J0D01*
G02X146270Y281507I3502J0D01*
G01X146307Y281521D01*
X146365Y281575D01*
G37*
G36*
G01X19766Y292430D02*
G02X21185Y292730I1418J-3202D01*
G02X22604Y292430I1J-3502D01*
G03X22766I81J182D01*
G02X24185Y292730I1418J-3202D01*
G02X25604Y292430I1J-3502D01*
G03X25766I81J182D01*
G02X27185Y292730I1418J-3202D01*
G02X30687Y289228I0J-3502D01*
G02X30387Y287809I-3502J-1D01*
G03Y287647I182J-81D01*
G02X30687Y286228I-3202J-1418D01*
G02X27185Y282726I-3502J0D01*
G02X25766Y283026I-1J3502D01*
G03X25604I-81J-182D01*
G02X24185Y282726I-1418J3202D01*
G02X22766Y283026I-1J3502D01*
G03X22604I-81J-182D01*
G02X21185Y282726I-1418J3202D01*
G02X19766Y283026I-1J3502D01*
G03X19604I-81J-182D01*
G02X18185Y282726I-1418J3202D01*
G02X15896Y283578I0J3501D01*
G01X15854Y283614D01*
X15750Y283633D01*
X15320Y283483D01*
X15251Y283403D01*
X15241Y283350D01*
G02X11800Y280498I-3441J650D01*
G02Y287502I0J3502D01*
G02X14089Y286650I0J-3501D01*
G01X14131Y286614D01*
X14235Y286595D01*
X14665Y286745D01*
X14734Y286825D01*
X14744Y286878D01*
G02X14983Y287647I3442J-648D01*
G03Y287809I-182J81D01*
G02X14683Y289228I3202J1418D01*
G02X18185Y292730I3502J0D01*
G02X19604Y292430I1J-3502D01*
G03X19766I81J182D01*
G37*
G36*
G01X129063D02*
G02X130482Y292730I1418J-3202D01*
G02X131901Y292430I1J-3502D01*
G03X132063I81J182D01*
G02X133482Y292730I1418J-3202D01*
G02X134901Y292430I1J-3502D01*
G03X135063I81J182D01*
G02X136482Y292730I1418J-3202D01*
G02X139984Y289228I0J-3502D01*
G02X139684Y287809I-3502J-1D01*
G03Y287647I182J-81D01*
G02X139984Y286228I-3202J-1418D01*
G02X136482Y282726I-3502J0D01*
G02X135063Y283026I-1J3502D01*
G03X134901I-81J-182D01*
G02X133482Y282726I-1418J3202D01*
G02X132063Y283026I-1J3502D01*
G03X131901I-81J-182D01*
G02X130482Y282726I-1418J3202D01*
G02X129063Y283026I-1J3502D01*
G03X128901I-81J-182D01*
G02X127482Y282726I-1418J3202D01*
G02X123980Y286228I0J3502D01*
G02X124280Y287647I3502J1D01*
G03Y287809I-182J81D01*
G02X123980Y289228I3202J1418D01*
G02X127482Y292730I3502J0D01*
G02X128901Y292430I1J-3502D01*
G03X129063I81J182D01*
G37*
G36*
G01X51714Y295038D02*
G02X48498Y298528I286J3490D01*
G02X49769Y301227I3501J0D01*
G03X49841Y301379I-128J154D01*
G02X53343Y304836I3502J-45D01*
G02X56750Y302144I0J-3502D01*
G03X56971Y301992I195J46D01*
G02X57430Y302022I457J-3472D01*
G02X58749Y301764I0J-3501D01*
G03X58964Y301807I75J185D01*
G02X61420Y302812I2455J-2497D01*
G02X63740Y301934I1J-3502D01*
G03X63909Y301887I133J149D01*
G02X64561Y301948I651J-3441D01*
G02Y294944I0J-3502D01*
G02X62241Y295822I-1J3502D01*
G03X62072Y295869I-133J-149D01*
G02X61420Y295808I-651J3441D01*
G02X60101Y296066I0J3501D01*
G03X59886Y296023I-75J-185D01*
G02X58145Y295092I-2455J2498D01*
G03X58009Y294991I40J-196D01*
G02X54926Y293149I-3083J1659D01*
G02X51873Y294936I0J3501D01*
G03X51714Y295038I-175J-98D01*
G37*
G36*
G01X164097Y294227D02*
G02X161761Y295307I199J3496D01*
G03X161529Y295349I-145J-138D01*
G02X160000Y294998I-1528J3151D01*
G02X156498Y298500I0J3502D01*
G02X159183Y301905I3502J0D01*
G03X159333Y302065I-47J194D01*
G02X162783Y304965I3450J-602D01*
G02X166285Y301463I0J-3502D01*
G02X166221Y300795I-3502J-2D01*
G03X166302Y300593I196J-39D01*
G02X166621Y300341I-2007J-2869D01*
G01X166657Y300310D01*
X166745Y300286D01*
X167148Y300361D01*
X167221Y300416D01*
X167243Y300458D01*
G02X170358Y302360I3115J-1600D01*
G02X172327Y301754I0J-3502D01*
G03X172516Y301735I112J166D01*
G02X173858Y302002I1341J-3235D01*
G02Y294998I0J-3502D01*
G02X171889Y295604I0J3502D01*
G03X171700Y295623I-112J-166D01*
G02X170510Y295359I-1342J3235D01*
G03X170329Y295222I9J-200D01*
G02X167000Y292808I-3329J1088D01*
G02X164243Y294150I0J3503D01*
G03X164097Y294227I-158J-123D01*
G37*
G36*
G01X37735Y297753D02*
X37510Y298176D01*
X37410Y298233D01*
X37351Y298230D01*
G02X37185Y298226I-167J3498D01*
G02Y305230I0J3502D01*
G02X38604Y304930I1J-3502D01*
G03X38766I81J182D01*
G02X40185Y305230I1418J-3202D01*
G02X42376Y304460I0J-3502D01*
G03X42609Y304448I125J156D01*
G02X44500Y305002I1890J-2948D01*
G02Y297998I0J-3502D01*
G02X43819Y298065I1J3502D01*
G01X43759Y298077D01*
X43647Y298030D01*
X43375Y297622D01*
Y297500D01*
X43409Y297450D01*
G02X44002Y295500I-2910J-1950D01*
G02X36998I-3502J0D01*
G02X37691Y297592I3502J1D01*
G01X37726Y297639D01*
X37735Y297753D01*
G37*
G36*
G01X146733Y297745D02*
X146530Y298165D01*
X146436Y298226D01*
X146380Y298227D01*
G02X142980Y301728I103J3501D01*
G02X146482Y305230I3502J0D01*
G02X147901Y304930I1J-3502D01*
G03X148063I81J182D01*
G02X149482Y305230I1418J-3202D01*
G02X152984Y301728I0J-3502D01*
G02X152754Y300480I-3501J0D01*
G01X152738Y300438D01*
X152745Y300350D01*
X152939Y300004D01*
X153011Y299952D01*
X153055Y299944D01*
G02X155922Y296500I-635J-3444D01*
G02X152420Y292998I-3502J0D01*
G02X152070Y293016I5J3502D01*
G03X151912Y292961I-19J-199D01*
G02X149500Y291998I-2412J2539D01*
G02X145998Y295500I0J3502D01*
G02X146689Y297589I3503J0D01*
G01X146723Y297634D01*
X146733Y297745D01*
G37*
G36*
G01X56389Y315830D02*
G02X56183Y317012I3296J1183D01*
G02X59685Y320514I3502J0D01*
G02X60886Y320301I-2J-3502D01*
G03X61024I69J188D01*
G02X62225Y320514I1203J-3289D01*
G02X63426Y320301I-2J-3502D01*
G03X63564I69J188D01*
G02X64765Y320514I1203J-3289D01*
G02X68267Y317012I0J-3502D01*
G02X68061Y315830I-3502J1D01*
G03Y315694I189J-68D01*
G02X68267Y314512I-3296J-1183D01*
G02X64765Y311010I-3502J0D01*
G02X63583Y311216I1J3502D01*
G03X63447I-68J-189D01*
G02X62265Y311010I-1183J3296D01*
G02X61045Y311229I-1J3502D01*
G03X60905I-70J-187D01*
G02X59685Y311010I-1219J3283D01*
G02X56183Y314512I0J3502D01*
G02X56389Y315694I3502J-1D01*
G03Y315830I-189J68D01*
G37*
G36*
G01X165686D02*
G02X165480Y317012I3296J1183D01*
G02X168982Y320514I3502J0D01*
G02X170183Y320301I-2J-3502D01*
G03X170321I69J188D01*
G02X171522Y320514I1203J-3289D01*
G02X172723Y320301I-2J-3502D01*
G03X172861I69J188D01*
G02X174062Y320514I1203J-3289D01*
G02X177564Y317012I0J-3502D01*
G02X177358Y315830I-3502J1D01*
G03Y315694I189J-68D01*
G02X177564Y314512I-3296J-1183D01*
G02X174062Y311010I-3502J0D01*
G02X172880Y311216I1J3502D01*
G03X172744I-68J-189D01*
G02X171562Y311010I-1183J3296D01*
G02X170342Y311229I-1J3502D01*
G03X170202I-70J-187D01*
G02X168982Y311010I-1219J3283D01*
G02X165480Y314512I0J3502D01*
G02X165686Y315694I3502J-1D01*
G03Y315830I-189J68D01*
G37*
G36*
G01X162060Y330647D02*
G02X162360Y329228I-3202J-1418D01*
G02X155356I-3502J0D01*
G02X155656Y330647I3502J1D01*
G03Y330809I-182J81D01*
G02X155356Y332228I3202J1418D01*
G02X162360I3502J0D01*
G02X162060Y330809I-3502J-1D01*
G03Y330647I182J-81D01*
G37*
G36*
G01X179039Y339030D02*
G02X180458Y339330I1418J-3202D01*
G02X181877Y339030I1J-3502D01*
G03X182039I81J182D01*
G02X183458Y339330I1418J-3202D01*
G02X184877Y339030I1J-3502D01*
G03X185039I81J182D01*
G02X186458Y339330I1418J-3202D01*
G02Y332326I0J-3502D01*
G02X185039Y332626I-1J3502D01*
G03X184877I-81J-182D01*
G02X183458Y332326I-1418J3202D01*
G02X182039Y332626I-1J3502D01*
G03X181877I-81J-182D01*
G02X180458Y332326I-1418J3202D01*
G02X179039Y332626I-1J3502D01*
G03X178877I-81J-182D01*
G02X177458Y332326I-1418J3202D01*
G02Y339330I0J3502D01*
G02X178877Y339030I1J-3502D01*
G03X179039I81J182D01*
G37*
G36*
G01X18581Y339130D02*
G02X20000Y339430I1418J-3202D01*
G02X21419Y339130I1J-3502D01*
G03X21581I81J182D01*
G02X23000Y339430I1418J-3202D01*
G02X24419Y339130I1J-3502D01*
G03X24581I81J182D01*
G02X26000Y339430I1418J-3202D01*
G02Y332426I0J-3502D01*
G02X24581Y332726I-1J3502D01*
G03X24419I-81J-182D01*
G02X23000Y332426I-1418J3202D01*
G02X21581Y332726I-1J3502D01*
G03X21419I-81J-182D01*
G02X20000Y332426I-1418J3202D01*
G02X18581Y332726I-1J3502D01*
G03X18419I-81J-182D01*
G02X17000Y332426I-1418J3202D01*
G02X15581Y332726I-1J3502D01*
G03X15419I-81J-182D01*
G02X14000Y332426I-1418J3202D01*
G02Y339430I0J3502D01*
G02X15419Y339130I1J-3502D01*
G03X15581I81J182D01*
G02X17000Y339430I1418J-3202D01*
G02X18419Y339130I1J-3502D01*
G03X18581I81J182D01*
G37*
G36*
G01X147856Y338390D02*
G02X148102Y337100I-3256J-1289D01*
G02X141098I-3502J0D01*
G02X141344Y338390I3502J1D01*
G03Y338538I-186J74D01*
G02X141098Y339828I3256J1289D01*
G02X148102I3502J0D01*
G02X147856Y338538I-3502J-1D01*
G03Y338390I186J-74D01*
G37*
G36*
G01X49704Y347315D02*
G02X49498Y348497I3296J1183D01*
G02X49704Y349679I3502J-1D01*
G03Y349815I-189J68D01*
G02X49498Y350997I3296J1183D01*
G02X56502I3502J0D01*
G02X56296Y349815I-3502J1D01*
G03Y349679I189J-68D01*
G02X56502Y348497I-3296J-1183D01*
G02X56296Y347315I-3502J1D01*
G03Y347179I189J-68D01*
G02X56501Y346060I-3296J-1182D01*
G03X56647Y345871I200J4D01*
G02X59202Y342500I-946J-3371D01*
G02X55700Y338998I-3502J0D01*
G02X52199Y342437I0J3502D01*
G03X52053Y342626I-200J-4D01*
G02X49498Y345997I946J3371D01*
G02X49704Y347179I3502J-1D01*
G03Y347315I-189J68D01*
G37*
G36*
G01X71404Y347318D02*
G02X71198Y348500I3296J1183D01*
G02X71404Y349682I3502J-1D01*
G03Y349818I-189J68D01*
G02X71198Y351000I3296J1183D01*
G02X78202I3502J0D01*
G02X77996Y349818I-3502J1D01*
G03Y349682I189J-68D01*
G02X78202Y348500I-3296J-1183D01*
G02X77996Y347318I-3502J1D01*
G03Y347182I189J-68D01*
G02X78202Y346000I-3296J-1183D01*
G02X76442Y342962I-3502J0D01*
G01X76407Y342942D01*
X76359Y342879D01*
X76266Y342522D01*
X76278Y342444D01*
X76299Y342409D01*
G02X76802Y340600I-2999J-1808D01*
G02X76596Y339418I-3502J1D01*
G03Y339282I189J-68D01*
G02X76802Y338100I-3296J-1183D01*
G02X69798I-3502J0D01*
G02X70004Y339282I3502J-1D01*
G03Y339418I-189J68D01*
G02X69798Y340600I3296J1183D01*
G02X71558Y343638I3502J0D01*
G01X71593Y343658D01*
X71641Y343721D01*
X71734Y344078D01*
X71722Y344156D01*
X71701Y344191D01*
G02X71198Y346000I2999J1808D01*
G02X71404Y347182I3502J-1D01*
G03Y347318I-189J68D01*
G37*
G36*
G01X124797Y346885D02*
G02X124498Y348300I3203J1416D01*
G02X124868Y349867I3503J0D01*
G03X124863Y350056I-179J90D01*
G02X124398Y351800I3038J1744D01*
G02X131402I3502J0D01*
G02X131032Y350233I-3503J0D01*
G03X131037Y350044I179J-90D01*
G02X131502Y348300I-3038J-1744D01*
G02X131109Y346688I-3503J0D01*
G03X131103Y346515I177J-93D01*
G02X131402Y345100I-3203J-1416D01*
G02X131126Y343737I-3502J0D01*
G01X131110Y343699D01*
Y343616D01*
X131262Y343274D01*
X131322Y343218D01*
X131362Y343204D01*
G02X133702Y339900I-1163J-3304D01*
G02X133496Y338718I-3502J1D01*
G03Y338582I189J-68D01*
G02X133702Y337400I-3296J-1183D01*
G02X126698I-3502J0D01*
G02X126904Y338582I3502J-1D01*
G03Y338718I-189J68D01*
G02X126698Y339900I3296J1183D01*
G02X126974Y341263I3502J0D01*
G01X126990Y341301D01*
Y341384D01*
X126838Y341726D01*
X126778Y341782D01*
X126738Y341796D01*
G02X124398Y345100I1163J3304D01*
G02X124791Y346712I3503J0D01*
G03X124797Y346885I-177J93D01*
G37*
G36*
G01X146644Y347738D02*
G02X146398Y349028I3256J1289D01*
G02X146653Y350339I3502J-1D01*
G03Y350489I-186J75D01*
G02X146398Y351800I3247J1312D01*
G02X153402I3502J0D01*
G02X153147Y350489I-3502J1D01*
G03Y350339I186J-75D01*
G02X153402Y349028I-3247J-1312D01*
G02X153156Y347738I-3502J-1D01*
G03Y347590I186J-74D01*
G02X153402Y346300I-3256J-1289D01*
G02X146398I-3502J0D01*
G02X146644Y347590I3502J1D01*
G03Y347738I-186J74D01*
G37*
G36*
G01X19081Y364930D02*
G02X20500Y365230I1418J-3202D01*
G02X21919Y364930I1J-3502D01*
G03X22081I81J182D01*
G02X23500Y365230I1418J-3202D01*
G02X24919Y364930I1J-3502D01*
G03X25081I81J182D01*
G02X26500Y365230I1418J-3202D01*
G02X30002Y361728I0J-3502D01*
G02X29702Y360309I-3502J-1D01*
G03Y360147I182J-81D01*
G02X30002Y358728I-3202J-1418D01*
G02X26500Y355226I-3502J0D01*
G02X25081Y355526I-1J3502D01*
G03X24919I-81J-182D01*
G02X23500Y355226I-1418J3202D01*
G02X22081Y355526I-1J3502D01*
G03X21919I-81J-182D01*
G02X20500Y355226I-1418J3202D01*
G02X19081Y355526I-1J3502D01*
G03X18919I-81J-182D01*
G02X17500Y355226I-1418J3202D01*
G02X13998Y358728I0J3502D01*
G02X14298Y360147I3502J1D01*
G03Y360309I-182J81D01*
G02X13998Y361728I3202J1418D01*
G02X17500Y365230I3502J0D01*
G02X18919Y364930I1J-3502D01*
G03X19081I81J182D01*
G37*
G36*
G01X178439Y365492D02*
G02X179858Y365792I1418J-3202D01*
G02X181277Y365492I1J-3502D01*
G03X181439I81J182D01*
G02X182858Y365792I1418J-3202D01*
G02X184277Y365492I1J-3502D01*
G03X184439I81J182D01*
G02X185858Y365792I1418J-3202D01*
G02X189360Y362290I0J-3502D01*
G02X189154Y361108I-3502J1D01*
G03Y360972I189J-68D01*
G02X189360Y359790I-3296J-1183D01*
G02X185858Y356288I-3502J0D01*
G02X184439Y356588I-1J3502D01*
G03X184277I-81J-182D01*
G02X182858Y356288I-1418J3202D01*
G02X181439Y356588I-1J3502D01*
G03X181277I-81J-182D01*
G02X179858Y356288I-1418J3202D01*
G02X178439Y356588I-1J3502D01*
G03X178277I-81J-182D01*
G02X176858Y356288I-1418J3202D01*
G02X173356Y359790I0J3502D01*
G02X173562Y360972I3502J-1D01*
G03Y361108I-189J68D01*
G02X173356Y362290I3296J1183D01*
G02X176858Y365792I3502J0D01*
G02X178277Y365492I1J-3502D01*
G03X178439I81J182D01*
G37*
G36*
G01X49704Y366315D02*
G02X49498Y367497I3296J1183D01*
G02X49704Y368679I3502J-1D01*
G03Y368815I-189J68D01*
G02X49498Y369997I3296J1183D01*
G02X56502I3502J0D01*
G02X56296Y368815I-3502J1D01*
G03Y368679I189J-68D01*
G02X56502Y367497I-3296J-1183D01*
G02X56296Y366315I-3502J1D01*
G03Y366179I189J-68D01*
G02X56502Y364997I-3296J-1183D01*
G02X49498I-3502J0D01*
G02X49704Y366179I3502J-1D01*
G03Y366315I-189J68D01*
G37*
G36*
G01X146748Y366001D02*
G02X146398Y367528I3152J1526D01*
G02X146653Y368839I3502J-1D01*
G03Y368989I-186J75D01*
G02X146398Y370300I3247J1312D01*
G02X153402I3502J0D01*
G02X153147Y368989I-3502J1D01*
G03Y368839I186J-75D01*
G02X153402Y367528I-3247J-1312D01*
G02X153052Y366001I-3502J-1D01*
G03Y365827I180J-87D01*
G02X153402Y364300I-3152J-1526D01*
G02X146398I-3502J0D01*
G02X146748Y365827I3502J1D01*
G03Y366001I-180J87D01*
G37*
G36*
G01X71132Y366818D02*
G02X70926Y368000I3296J1183D01*
G02X71132Y369182I3502J-1D01*
G03Y369318I-189J68D01*
G02X70926Y370500I3296J1183D01*
G02X77930I3502J0D01*
G02X77724Y369318I-3502J1D01*
G03Y369182I189J-68D01*
G02X77930Y368000I-3296J-1183D01*
G02X77724Y366818I-3502J1D01*
G03Y366682I189J-68D01*
G02X77930Y365500I-3296J-1183D01*
G02X70926I-3502J0D01*
G02X71132Y366682I3502J-1D01*
G03Y366818I-189J68D01*
G37*
G36*
G01X124840Y366197D02*
G02X124398Y367900I3060J1703D01*
G02X124653Y369212I3503J0D01*
G03X124648Y369374I-185J75D01*
G02X124298Y370900I3152J1526D01*
G02X131302I3502J0D01*
G02X131047Y369588I-3503J0D01*
G03X131052Y369426I185J-75D01*
G02X131402Y367900I-3152J-1526D01*
G02X130960Y366197I-3502J0D01*
G03Y366003I175J-97D01*
G02X131402Y364300I-3060J-1703D01*
G02X124398I-3502J0D01*
G02X124840Y366003I3502J0D01*
G03Y366197I-175J97D01*
G37*
G36*
G01X115499Y401440D02*
X115522Y401556D01*
G03X115497Y401698I-196J39D01*
G02X114998Y403500I3004J1802D01*
G02X122002I3502J0D01*
G02X120579Y400682I-3502J0D01*
G03X120501Y400560I118J-162D01*
G01X120478Y400444D01*
G03X120503Y400302I196J-39D01*
G02X121002Y398500I-3004J-1802D01*
G02X117500Y394998I-3502J0D01*
G02X116961Y395040I2J3502D01*
G01X116916Y395047D01*
X116831Y395022D01*
X116533Y394757D01*
X116498Y394675D01*
X116500Y394630D01*
G02X116502Y394500I-3500J-119D01*
G02X113278Y391009I-3502J0D01*
G03X113116Y390901I16J-199D01*
G02X110610Y389052I-3115J1600D01*
G03X110448Y388890I35J-197D01*
G02X107000Y385998I-3448J609D01*
G02X103498Y389500I0J3502D01*
G02X106390Y392948I3501J0D01*
G03X106552Y393110I-35J197D01*
G02X109722Y395991I3448J-610D01*
G03X109884Y396099I-16J199D01*
G02X113000Y398002I3116J-1600D01*
G02X113539Y397960I-2J-3502D01*
G01X113584Y397953D01*
X113669Y397978D01*
X113967Y398243D01*
X114002Y398325D01*
X114000Y398370D01*
G02X113998Y398500I3500J119D01*
G02X115421Y401318I3502J0D01*
G03X115499Y401440I-118J162D01*
G37*
G36*
G01X63893Y415870D02*
G02X65900Y416502I2007J-2871D01*
G02Y409498I0J-3502D01*
G02X64422Y409825I0J3502D01*
G03X64223Y409808I-85J-181D01*
G02X62216Y409176I-2007J2871D01*
G02Y416180I0J3502D01*
G02X63694Y415853I0J-3502D01*
G03X63893Y415870I85J181D01*
G37*
G36*
G01X78722Y416382D02*
X78438Y416733D01*
X78340Y416772D01*
X78287Y416764D01*
G02X77773Y416726I-514J3464D01*
G02X81275Y420228I0J3502D01*
G02X81053Y419000I-3502J-1D01*
G01X81034Y418950D01*
X81051Y418846D01*
X81335Y418495D01*
X81433Y418456D01*
X81486Y418464D01*
G02X82000Y418502I514J-3464D01*
G02X85502Y415000I0J-3502D01*
G02X82217Y411505I-3502J0D01*
G01X82171Y411502D01*
X82092Y411458D01*
X81860Y411126D01*
X81845Y411037D01*
X81858Y410992D01*
G02X82002Y410000I-3358J-994D01*
G02X81447Y408108I-3502J0D01*
G03Y407892I168J-108D01*
G02X81841Y407049I-2947J-1891D01*
G01X81856Y407003D01*
X81923Y406934D01*
X82322Y406801D01*
X82417Y406816D01*
X82456Y406844D01*
G02X84500Y407502I2043J-2844D01*
G02X88002Y404000I0J-3502D01*
G02X85549Y400659I-3502J0D01*
G01X85503Y400644D01*
X85434Y400577D01*
X85301Y400178D01*
X85316Y400083D01*
X85344Y400044D01*
G02X86002Y398000I-2844J-2043D01*
G02X78998I-3502J0D01*
G02X81451Y401341I3502J0D01*
G01X81497Y401356D01*
X81566Y401423D01*
X81699Y401822D01*
X81684Y401917D01*
X81656Y401956D01*
G02X81159Y402951I2845J2043D01*
G01X81144Y402997D01*
X81077Y403066D01*
X80678Y403199D01*
X80583Y403184D01*
X80544Y403156D01*
G02X78500Y402498I-2043J2844D01*
G02X74998Y406000I0J3502D01*
G02X75553Y407892I3502J0D01*
G03Y408108I-168J108D01*
G02X74998Y410000I2947J1892D01*
G02X78283Y413495I3502J0D01*
G01X78329Y413498D01*
X78408Y413542D01*
X78640Y413874D01*
X78655Y413963D01*
X78642Y414008D01*
G02X78498Y415000I3358J994D01*
G02X78720Y416228I3502J1D01*
G01X78739Y416278D01*
X78722Y416382D01*
G37*
G36*
G01X63256Y426856D02*
G02X63977Y424728I-2780J-2128D01*
G02X56973I-3502J0D01*
G02X57694Y426856I3501J0D01*
G03Y427100I-159J122D01*
G02X56973Y429228I2780J2128D01*
G02X60475Y432730I3502J0D01*
G02X63052Y431599I0J-3501D01*
G01X63088Y431560D01*
X63186Y431528D01*
X63624Y431614D01*
X63702Y431680D01*
X63721Y431730D01*
G02X67000Y434002I3279J-1230D01*
G02X70484Y430859I0J-3502D01*
G01X70487Y430821D01*
X70522Y430755D01*
X70785Y430524D01*
X70855Y430499D01*
X70894Y430500D01*
G02X71000Y430502I119J-3500D01*
G02X74502Y427000I0J-3502D01*
G02X71668Y423562I-3502J0D01*
G01X71613Y423552D01*
X71530Y423477D01*
X71397Y423030D01*
X71425Y422923D01*
X71465Y422883D01*
G02X72520Y420378I-2446J-2505D01*
G02X65516I-3502J0D01*
G02X68350Y423816I3502J0D01*
G01X68405Y423826D01*
X68488Y423901D01*
X68621Y424348D01*
X68593Y424455D01*
X68553Y424495D01*
G02X67516Y426641I2447J2506D01*
G01X67513Y426679D01*
X67478Y426745D01*
X67215Y426976D01*
X67145Y427001D01*
X67106Y427000D01*
G02X67000Y426998I-119J3500D01*
G02X64423Y428129I0J3501D01*
G01X64387Y428168D01*
X64289Y428200D01*
X63851Y428114D01*
X63773Y428048D01*
X63754Y427998D01*
G02X63256Y427100I-3278J1231D01*
G03Y426856I159J-122D01*
G37*
G36*
G01X132534Y429206D02*
X132170Y429375D01*
X132080Y429374D01*
X132039Y429354D01*
G02X130500Y428998I-1538J3146D01*
G02Y436002I0J3502D01*
G02X133897Y433349I0J-3501D01*
G01X133909Y433305D01*
X133966Y433235D01*
X134330Y433066D01*
X134420Y433067D01*
X134461Y433087D01*
G02X136000Y433443I1538J-3146D01*
G02X137781Y432956I0J-3502D01*
G03X137951Y432940I102J172D01*
G02X139150Y433152I1200J-3290D01*
G02X142084Y431562I0J-3502D01*
G03X142277Y431473I167J109D01*
G02X142727Y431502I450J-3473D01*
G02Y424498I0J-3502D01*
G02X139793Y426088I0J3502D01*
G03X139600Y426177I-167J-109D01*
G02X139150Y426148I-450J3473D01*
G02X137369Y426635I0J3502D01*
G03X137199Y426651I-102J-172D01*
G02X136000Y426439I-1200J3290D01*
G02X132603Y429092I0J3501D01*
G01X132591Y429136D01*
X132534Y429206D01*
G37*
G36*
G01X88963Y436489D02*
X88966Y436607D01*
G03X88918Y436739I-200J2D01*
G02X88091Y439000I2675J2260D01*
G02X95095I3502J0D01*
G02X94182Y436642I-3501J0D01*
G03X94130Y436511I148J-135D01*
G01X94127Y436393D01*
G03X94175Y436261I200J-2D01*
G02X95002Y434000I-2675J-2260D01*
G02X87998I-3502J0D01*
G02X88911Y436358I3501J0D01*
G03X88963Y436489I-148J135D01*
G37*
G36*
G01X107009Y445282D02*
G02X110500Y448502I3491J-282D01*
G02X114002Y445000I0J-3502D01*
G02X110538Y441498I-3502J0D01*
G03X110341Y441314I2J-200D01*
G02X106850Y438094I-3491J282D01*
G02X103348Y441596I0J3502D01*
G02X106812Y445098I3502J0D01*
G03X107009Y445282I-2J200D01*
G37*
G36*
G01X61507Y447192D02*
X61810Y447441D01*
X61848Y447520D01*
X61849Y447564D01*
G02X65350Y451002I3501J-64D01*
G02X68852Y447500I0J-3502D01*
G02X68841Y447224I-3502J1D01*
G01X68837Y447174D01*
X68878Y447082D01*
X69222Y446814D01*
X69321Y446798D01*
X69369Y446814D01*
G02X70500Y447002I1132J-3314D01*
G02X66998Y443500I0J-3502D01*
G02X67009Y443776I3502J-1D01*
G01X67013Y443826D01*
X66972Y443918D01*
X66628Y444186D01*
X66529Y444202D01*
X66481Y444186D01*
G02X65350Y443998I-1132J3314D01*
G02X64744Y444051I1J3502D01*
G01X64700Y444059D01*
X64616Y444036D01*
X64313Y443787D01*
X64275Y443708D01*
X64274Y443664D01*
G02X62059Y440471I-3501J64D01*
G03X61936Y440323I73J-186D01*
G02X58500Y437498I-3436J677D01*
G02X54998Y441000I0J3502D01*
G02X57214Y444257I3502J0D01*
G03X57337Y444405I-73J186D01*
G02X60773Y447230I3436J-677D01*
G02X61379Y447177I-1J-3502D01*
G01X61423Y447169D01*
X61507Y447192D01*
G37*
G36*
G01X57337Y457905D02*
G02X60773Y460730I3436J-677D01*
G02X64275Y457228I0J-3502D01*
G02X62059Y453971I-3502J0D01*
G03X61936Y453823I73J-186D01*
G02X58500Y450998I-3436J677D01*
G02X54998Y454500I0J3502D01*
G02X57214Y457757I3502J0D01*
G03X57337Y457905I-73J186D01*
G37*
G36*
G01X22735Y463244D02*
Y463606D01*
X22706Y463678D01*
X22677Y463706D01*
G02X21176Y467362I3702J3656D01*
G02X26378Y472564I5202J0D01*
G02X30034Y471063I0J-5203D01*
G01X30062Y471034D01*
X30134Y471005D01*
X30496D01*
X30568Y471034D01*
X30596Y471063D01*
G02X34252Y472564I3656J-3702D01*
G02X39454Y467362I0J-5202D01*
G02X37953Y463706I-5203J0D01*
G01X37924Y463678D01*
X37895Y463606D01*
Y463244D01*
X37924Y463172D01*
X37953Y463144D01*
G02Y455832I-3702J-3656D01*
G01X37924Y455804D01*
X37895Y455732D01*
Y455370D01*
X37924Y455298D01*
X37953Y455270D01*
G02Y447958I-3702J-3656D01*
G01X37924Y447930D01*
X37895Y447858D01*
Y447496D01*
X37924Y447424D01*
X37953Y447396D01*
G02Y440084I-3702J-3656D01*
G01X37924Y440056D01*
X37895Y439984D01*
Y439622D01*
X37924Y439550D01*
X37953Y439522D01*
G02Y432210I-3702J-3656D01*
G01X37924Y432182D01*
X37895Y432110D01*
Y431748D01*
X37924Y431676D01*
X37953Y431648D01*
G02Y424336I-3702J-3656D01*
G01X37924Y424308D01*
X37895Y424236D01*
Y423874D01*
X37924Y423802D01*
X37953Y423774D01*
G02Y416462I-3702J-3656D01*
G01X37924Y416434D01*
X37895Y416362D01*
Y416000D01*
X37924Y415928D01*
X37953Y415900D01*
G02X39454Y412244I-3702J-3656D01*
G02X35216Y407132I-5202J0D01*
G01X35171Y407124D01*
X35099Y407072D01*
X34907Y406722D01*
X34901Y406633D01*
X34918Y406591D01*
G02X25712I-4603J-1827D01*
G01X25729Y406633D01*
X25723Y406722D01*
X25531Y407072D01*
X25459Y407124D01*
X25414Y407132D01*
G02X21176Y412244I964J5112D01*
G02X22677Y415900I5203J0D01*
G01X22706Y415928D01*
X22735Y416000D01*
Y416362D01*
X22706Y416434D01*
X22677Y416462D01*
G02Y423774I3702J3656D01*
G01X22706Y423802D01*
X22735Y423874D01*
Y424236D01*
X22706Y424308D01*
X22677Y424336D01*
G02Y431648I3702J3656D01*
G01X22706Y431676D01*
X22735Y431748D01*
Y432110D01*
X22706Y432182D01*
X22677Y432210D01*
G02Y439522I3702J3656D01*
G01X22706Y439550D01*
X22735Y439622D01*
Y439984D01*
X22706Y440056D01*
X22677Y440084D01*
G02Y447396I3702J3656D01*
G01X22706Y447424D01*
X22735Y447496D01*
Y447858D01*
X22706Y447930D01*
X22677Y447958D01*
G02Y455270I3702J3656D01*
G01X22706Y455298D01*
X22735Y455370D01*
Y455732D01*
X22706Y455804D01*
X22677Y455832D01*
G02Y463144I3702J3656D01*
G01X22706Y463172D01*
X22735Y463244D01*
G37*
G36*
G01X132055Y466288D02*
G02X129000Y464498I-3055J1712D01*
G02X126101Y466036I0J3501D01*
G03X125912Y466122I-165J-113D01*
G02X125500Y466098I-409J3478D01*
G02Y473102I0J3502D01*
G02X128399Y471564I0J-3501D01*
G03X128588Y471478I165J113D01*
G02X129000Y471502I409J-3478D01*
G02X131643Y470297I0J-3501D01*
G01X131675Y470260D01*
X131766Y470225D01*
X132189Y470268D01*
X132270Y470321D01*
X132294Y470364D01*
G02X135349Y472154I3055J-1712D01*
G02X138851Y468652I0J-3502D01*
G02X137597Y465967I-3501J0D01*
G01X137565Y465940D01*
X137529Y465868D01*
X137506Y465495D01*
X137533Y465419D01*
X137562Y465388D01*
G02X138502Y463000I-2563J-2388D01*
G02X131498I-3502J0D01*
G02X132752Y465685I3501J0D01*
G01X132784Y465712D01*
X132820Y465784D01*
X132843Y466157D01*
X132816Y466233D01*
X132787Y466264D01*
G02X132706Y466355I2575J2374D01*
G01X132674Y466392D01*
X132583Y466427D01*
X132160Y466384D01*
X132079Y466331D01*
X132055Y466288D01*
G37*
G36*
G01X150782Y472469D02*
X150626Y472812D01*
X150565Y472867D01*
X150525Y472881D01*
G02X148133Y476202I1109J3321D01*
G02X155137I3502J0D01*
G02X154867Y474855I-3502J1D01*
G01X154851Y474816D01*
X154853Y474733D01*
X155009Y474390D01*
X155070Y474335D01*
X155110Y474321D01*
G02X157502Y471000I-1109J-3321D01*
G02X150498I-3502J0D01*
G02X150768Y472347I3502J-1D01*
G01X150784Y472386D01*
X150782Y472469D01*
G37*
G36*
G01X168444Y472534D02*
X168636Y472884D01*
X168642Y472973D01*
X168625Y473015D01*
G02X177831I4603J1827D01*
G01X177814Y472973D01*
X177820Y472884D01*
X178012Y472534D01*
X178084Y472482D01*
X178129Y472474D01*
G02X182367Y467362I-964J-5112D01*
G02X180866Y463706I-5203J0D01*
G01X180837Y463678D01*
X180808Y463606D01*
Y463244D01*
X180837Y463172D01*
X180866Y463144D01*
G02Y455832I-3702J-3656D01*
G01X180837Y455804D01*
X180808Y455732D01*
Y455370D01*
X180837Y455298D01*
X180866Y455270D01*
G02Y447958I-3702J-3656D01*
G01X180837Y447930D01*
X180808Y447858D01*
Y447496D01*
X180837Y447424D01*
X180866Y447396D01*
G02Y440084I-3702J-3656D01*
G01X180837Y440056D01*
X180808Y439984D01*
Y439622D01*
X180837Y439550D01*
X180866Y439522D01*
G02Y432210I-3702J-3656D01*
G01X180837Y432182D01*
X180808Y432110D01*
Y431748D01*
X180837Y431676D01*
X180866Y431648D01*
G02Y424336I-3702J-3656D01*
G01X180837Y424308D01*
X180808Y424236D01*
Y423874D01*
X180837Y423802D01*
X180866Y423774D01*
G02Y416462I-3702J-3656D01*
G01X180837Y416434D01*
X180808Y416362D01*
Y416000D01*
X180837Y415928D01*
X180866Y415900D01*
G02X182367Y412244I-3702J-3656D01*
G02X177165Y407042I-5202J0D01*
G02X173509Y408543I0J5203D01*
G01X173481Y408572D01*
X173409Y408601D01*
X173047D01*
X172975Y408572D01*
X172947Y408543D01*
G02X169291Y407042I-3656J3702D01*
G02X164089Y412244I0J5202D01*
G02X165590Y415900I5203J0D01*
G01X165619Y415928D01*
X165648Y416000D01*
Y416362D01*
X165619Y416434D01*
X165590Y416462D01*
G02Y423774I3702J3656D01*
G01X165619Y423802D01*
X165648Y423874D01*
Y424236D01*
X165619Y424308D01*
X165590Y424336D01*
G02Y431648I3702J3656D01*
G01X165619Y431676D01*
X165648Y431748D01*
Y432110D01*
X165619Y432182D01*
X165590Y432210D01*
G02Y439522I3702J3656D01*
G01X165619Y439550D01*
X165648Y439622D01*
Y439984D01*
X165619Y440056D01*
X165590Y440084D01*
G02Y447396I3702J3656D01*
G01X165619Y447424D01*
X165648Y447496D01*
Y447858D01*
X165619Y447930D01*
X165590Y447958D01*
G02Y455270I3702J3656D01*
G01X165619Y455298D01*
X165648Y455370D01*
Y455732D01*
X165619Y455804D01*
X165590Y455832D01*
G02Y463144I3702J3656D01*
G01X165619Y463172D01*
X165648Y463244D01*
Y463606D01*
X165619Y463678D01*
X165590Y463706D01*
G02X164089Y467362I3702J3656D01*
G02X168327Y472474I5202J0D01*
G01X168372Y472482D01*
X168444Y472534D01*
G37*
G36*
G01X83499Y483377D02*
X83371Y483746D01*
X83312Y483808D01*
X83271Y483825D01*
G02X81073Y487075I1304J3250D01*
G02X88077I3502J0D01*
G02X87606Y485322I-3502J1D01*
G01X87584Y485283D01*
X87576Y485198D01*
X87704Y484829D01*
X87763Y484767D01*
X87804Y484750D01*
G02X90002Y481500I-1304J-3250D01*
G02X82998I-3502J0D01*
G02X83469Y483253I3502J-1D01*
G01X83491Y483292D01*
X83499Y483377D01*
G37*
G36*
G01X16998Y495001D02*
G02X17204Y496182I3502J-2D01*
G03Y496318I-189J68D01*
G02X16998Y497500I3296J1183D01*
G02X24002I3502J0D01*
G02X23796Y496318I-3502J1D01*
G03Y496182I189J-68D01*
G02X24002Y495000I-3296J-1183D01*
G02X21637Y491688I-3502J0D01*
G03X21502Y491499I65J-189D01*
G02X18000Y487998I-3502J1D01*
G02X14498Y491500I0J3502D01*
G02X16863Y494812I3502J0D01*
G03X16998Y495001I-65J189D01*
G37*
G36*
G01X130454Y501347D02*
X130047Y501584D01*
X129936Y501582D01*
X129888Y501551D01*
G02X128000Y500998I-1889J2949D01*
G02X131502Y504500I0J3502D01*
G02X131497Y504308I-3502J-5D01*
G01X131494Y504251D01*
X131546Y504153D01*
X131953Y503916D01*
X132064Y503918D01*
X132112Y503949D01*
G02X134000Y504502I1889J-2949D01*
G02X130498Y501000I0J-3502D01*
G02X130503Y501192I3502J5D01*
G01X130506Y501249D01*
X130454Y501347D01*
G37*
G36*
G01X108127Y508089D02*
X107960Y508489D01*
X107882Y508553D01*
X107833Y508562D01*
G02X104998Y512000I667J3438D01*
G02X112002I3502J0D01*
G02X111411Y510053I-3503J0D01*
G01X111383Y510011D01*
X111373Y509911D01*
X111540Y509511D01*
X111618Y509447D01*
X111667Y509438D01*
G02X114502Y506000I-667J-3438D01*
G02X113516Y503564I-3502J0D01*
G01X113482Y503529D01*
X113454Y503439D01*
X113526Y503025D01*
X113582Y502949D01*
X113626Y502928D01*
G02X115572Y499790I-1557J-3138D01*
G02X112070Y496288I-3502J0D01*
G02X110401Y496712I1J3502D01*
G03X110235Y496723I-95J-176D01*
G02X109375Y496518I-1236J3277D01*
G03X109199Y496348I22J-199D01*
G02X108870Y495288I-3467J495D01*
G03X108871Y495108I179J-89D01*
G02X109262Y493500I-3111J-1608D01*
G02X108418Y491219I-3502J-1D01*
G03X108369Y491087I151J-131D01*
G01X108371Y490970D01*
G03X108422Y490839I200J2D01*
G02X109313Y488657I-2608J-2338D01*
G03X109486Y488468I200J9D01*
G02X111128Y487781I-486J-3468D01*
G03X111372I122J159D01*
G02X113500Y488502I2128J-2780D01*
G02X115968Y487484I0J-3501D01*
G01X115997Y487456D01*
X116069Y487426D01*
X116431D01*
X116503Y487456D01*
X116532Y487484D01*
G02X121468I2468J-2483D01*
G01X121497Y487456D01*
X121569Y487426D01*
X121931D01*
X122003Y487456D01*
X122032Y487484D01*
G02X124500Y488502I2468J-2483D01*
G02X126957Y487496I0J-3502D01*
G01X126986Y487467D01*
X127058Y487438D01*
X127420Y487440D01*
X127492Y487470D01*
X127521Y487498D01*
G02X130000Y488527I2479J-2472D01*
G02X132469Y487509I0J-3503D01*
G01X132497Y487480D01*
X132569Y487451D01*
X132932D01*
X133004Y487480D01*
X133032Y487509D01*
G02X135500Y488526I2468J-2486D01*
G02Y481522I0J-3502D01*
G02X133031Y482540I0J3503D01*
G01X133003Y482569D01*
X132931Y482598D01*
X132568D01*
X132496Y482569D01*
X132468Y482540D01*
G02X130000Y481523I-2468J2486D01*
G02X127543Y482529I0J3502D01*
G01X127514Y482558D01*
X127442Y482587D01*
X127080Y482585D01*
X127008Y482555D01*
X126979Y482527D01*
G02X124500Y481498I-2479J2472D01*
G02X122032Y482516I0J3501D01*
G01X122003Y482544D01*
X121931Y482574D01*
X121569D01*
X121497Y482544D01*
X121468Y482516D01*
G02X116532I-2468J2483D01*
G01X116503Y482544D01*
X116431Y482574D01*
X116069D01*
X115997Y482544D01*
X115968Y482516D01*
G02X113500Y481498I-2468J2483D01*
G02X111372Y482219I0J3501D01*
G03X111128I-122J-159D01*
G02X109000Y481498I-2128J2780D01*
G02X107757Y481726I0J3502D01*
G03X107514Y481641I-71J-187D01*
G02X107115Y481096I-3012J1787D01*
G03Y480829I149J-134D01*
G02X108002Y478500I-2614J-2329D01*
G02X100998I-3502J0D01*
G02X101885Y480829I3501J0D01*
G03Y481096I-149J134D01*
G02X100998Y483425I2614J2329D01*
G02X102660Y486405I3503J0D01*
G03X102749Y486525I-105J171D01*
G01X102779Y486641D01*
G03X102760Y486789I-194J50D01*
G02X102313Y488500I3055J1712D01*
G02X103157Y490781I3502J1D01*
G03X103206Y490913I-151J131D01*
G01X103204Y491030D01*
G03X103153Y491161I-200J-2D01*
G02X102258Y493500I2607J2338D01*
G02X102622Y495056I3502J1D01*
G03X102621Y495236I-179J89D01*
G02X102230Y496844I3111J1608D01*
G02X105357Y500326I3502J0D01*
G03X105533Y500496I-22J199D01*
G02X107951Y503341I3467J-496D01*
G01X107997Y503356D01*
X108066Y503423D01*
X108199Y503822D01*
X108184Y503917D01*
X108156Y503956D01*
G02X107498Y506000I2844J2043D01*
G02X108089Y507947I3503J0D01*
G01X108117Y507989D01*
X108127Y508089D01*
G37*
G36*
G01X8219Y517872D02*
G02X7498Y520000I2780J2128D01*
G02X7887Y521605I3502J1D01*
G03Y521790I-177J93D01*
G02X7485Y523418I3100J1629D01*
G02X14489I3502J0D01*
G02X14100Y521813I-3502J-1D01*
G03Y521628I177J-93D01*
G02X14502Y520000I-3100J-1629D01*
G02X13781Y517872I-3501J0D01*
G03Y517628I159J-122D01*
G02Y513372I-2780J-2128D01*
G03Y513128I159J-122D01*
G02Y508872I-2780J-2128D01*
G03Y508628I159J-122D01*
G02Y504372I-2780J-2128D01*
G03Y504128I159J-122D01*
G02X14502Y502000I-2780J-2128D01*
G02X7498I-3502J0D01*
G02X8219Y504128I3501J0D01*
G03Y504372I-159J122D01*
G02Y508628I2780J2128D01*
G03Y508872I-159J122D01*
G02Y513128I2780J2128D01*
G03Y513372I-159J122D01*
G02Y517628I2780J2128D01*
G03Y517872I-159J122D01*
G37*
G36*
G01X75984Y521313D02*
X76230Y521700D01*
X76234Y521807D01*
X76208Y521856D01*
G02X75791Y523513I3084J1657D01*
G02X79293Y520011I3502J0D01*
G02X79109Y520016I3J3502D01*
G01X79054Y520019D01*
X78959Y519970D01*
X78713Y519583D01*
X78709Y519476D01*
X78735Y519427D01*
G02X79152Y517770I-3084J-1657D01*
G02X78903Y516473I-3502J0D01*
G01X78886Y516431D01*
X78891Y516343D01*
X79080Y515994D01*
X79151Y515941D01*
X79195Y515932D01*
G02X82002Y512500I-695J-3432D01*
G02X78500Y508998I-3502J0D01*
G02X75158Y511454I0J3502D01*
G03X74949Y511593I-191J-60D01*
G02X74626Y511578I-324J3487D01*
G02X71124Y515080I0J3502D01*
G02X72095Y517500I3501J0D01*
G03X72150Y517646I-145J138D01*
G02X72148Y517770I3500J118D01*
G02X75650Y521272I3502J0D01*
G02X75834Y521267I-3J-3502D01*
G01X75889Y521264D01*
X75984Y521313D01*
G37*
G36*
G01X95380Y523190D02*
X95442Y523289D01*
G03X95470Y523428I-169J106D01*
G02X95423Y524000I3455J572D01*
G02X102427I3502J0D01*
G02X99932Y520646I-3502J0D01*
G03X99820Y520560I58J-191D01*
G01X99758Y520461D01*
G03X99730Y520322I169J-106D01*
G02X99777Y519750I-3455J-572D01*
G02X99657Y518842I-3502J1D01*
G01X99647Y518804D01*
X99657Y518727D01*
X99831Y518415D01*
X99891Y518366D01*
X99929Y518355D01*
G02X102427Y515000I-1004J-3355D01*
G02X102221Y513818I-3502J1D01*
G03Y513682I189J-68D01*
G02X102427Y512500I-3296J-1183D01*
G02X100825Y509558I-3502J0D01*
G01X100789Y509535D01*
X100743Y509463D01*
X100684Y509083D01*
X100707Y509000D01*
X100734Y508967D01*
G02X101542Y506730I-2693J-2237D01*
G02X99821Y503714I-3503J0D01*
G03X99732Y503603I101J-172D01*
G01X99696Y503491D01*
G03X99704Y503349I190J-60D01*
G02X100004Y501930I-3202J-1418D01*
G02X93000I-3502J0D01*
G02X94721Y504946I3503J0D01*
G03X94810Y505057I-101J172D01*
G01X94846Y505169D01*
G03X94838Y505311I-190J60D01*
G02X94538Y506730I3202J1418D01*
G02X96140Y509672I3502J0D01*
G01X96176Y509695D01*
X96222Y509767D01*
X96281Y510147D01*
X96258Y510230D01*
X96231Y510263D01*
G02X95423Y512500I2693J2237D01*
G02X95629Y513682I3502J-1D01*
G03Y513818I-189J68D01*
G02X95423Y515000I3296J1183D01*
G02X95543Y515908I3502J-1D01*
G01X95553Y515946D01*
X95543Y516023D01*
X95369Y516335D01*
X95309Y516384D01*
X95271Y516395D01*
G02X92773Y519750I1004J3355D01*
G02X95268Y523104I3502J0D01*
G03X95380Y523190I-58J191D01*
G37*
G36*
G01X113147Y526484D02*
G03X113403Y527150I-41J398D01*
G02X112498Y529500I2597J2349D01*
G02X119502I3502J0D01*
G02X116353Y526016I-3502J0D01*
G03X116097Y525350I41J-398D01*
G02X117002Y523000I-2597J-2349D01*
G02X109998I-3502J0D01*
G02X113147Y526484I3502J0D01*
G37*
G36*
G01X95023Y534393D02*
X95420Y534562D01*
X95481Y534637D01*
X95491Y534687D01*
G02X98925Y537502I3434J-687D01*
G02X100415Y537169I0J-3502D01*
G03X100585I85J181D01*
G02X102075Y537502I1490J-3169D01*
G02Y530498I0J-3502D01*
G02X100585Y530831I0J3502D01*
G03X100415I-85J-181D01*
G02X98925Y530498I-1490J3169D01*
G02X97041Y531048I0J3502D01*
G01X96999Y531075D01*
X96902Y531083D01*
X96505Y530914D01*
X96444Y530839D01*
X96434Y530789D01*
G02X93000Y527974I-3434J687D01*
G02X90532Y528992I0J3501D01*
G01X90503Y529020D01*
X90431Y529050D01*
X90069D01*
X89997Y529020D01*
X89968Y528992D01*
G02X87500Y527974I-2468J2483D01*
G02X85370Y528696I0J3503D01*
G03X85220Y528735I-121J-159D01*
G02X84723Y528700I-494J3467D01*
G02X84269Y528730I3J3502D01*
G03X84122Y528690I-25J-199D01*
G02X82000Y527974I-2122J2786D01*
G02X79532Y528992I0J3501D01*
G01X79503Y529020D01*
X79431Y529050D01*
X79069D01*
X78997Y529020D01*
X78968Y528992D01*
G02X76500Y527974I-2468J2483D01*
G02Y534978I0J3502D01*
G02X78968Y533960I0J-3501D01*
G01X78997Y533932D01*
X79069Y533902D01*
X79431D01*
X79503Y533932D01*
X79532Y533960D01*
G02X82000Y534978I2468J-2483D01*
G02X82454Y534948I-3J-3502D01*
G03X82601Y534988I25J199D01*
G02X84723Y535704I2122J-2786D01*
G02X86853Y534982I0J-3503D01*
G03X87003Y534943I121J159D01*
G02X87500Y534978I494J-3467D01*
G02X89968Y533960I0J-3501D01*
G01X89997Y533932D01*
X90069Y533902D01*
X90431D01*
X90503Y533932D01*
X90532Y533960D01*
G02X93000Y534978I2468J-2483D01*
G02X94884Y534428I0J-3502D01*
G01X94926Y534401D01*
X95023Y534393D01*
G37*
G36*
G01X26447Y531697D02*
X26574Y532078D01*
X26564Y532166D01*
X26539Y532205D01*
G02X25998Y534075I2961J1870D01*
G02X29500Y537577I3502J0D01*
G02X32185Y536323I0J-3501D01*
G01X32214Y536289D01*
X32294Y536251D01*
X32690D01*
X32770Y536289D01*
X32799Y536323D01*
G02X35484Y537577I2685J-2247D01*
G02Y530573I0J-3502D01*
G02X32799Y531827I0J3501D01*
G01X32770Y531861D01*
X32690Y531899D01*
X32294D01*
X32214Y531861D01*
X32185Y531827D01*
G02X30738Y530799I-2685J2248D01*
G01X30695Y530783D01*
X30633Y530719D01*
X30506Y530338D01*
X30516Y530250D01*
X30541Y530211D01*
G02X31082Y528341I-2961J-1870D01*
G02X24078I-3502J0D01*
G02X26342Y531617I3502J0D01*
G01X26385Y531633D01*
X26447Y531697D01*
G37*
G36*
G01X182169Y533415D02*
G02X182502Y531925I-3169J-1490D01*
G02X175498I-3502J0D01*
G02X175831Y533415I3502J0D01*
G03Y533585I-181J85D01*
G02X175498Y535075I3169J1490D01*
G02X182502I3502J0D01*
G02X182169Y533585I-3502J0D01*
G03Y533415I181J-85D01*
G37*
G36*
G01X54379Y535980D02*
X54381Y536097D01*
G03X54333Y536230I-200J3D01*
G02X53498Y538500I2668J2270D01*
G02X60502I3502J0D01*
G02X59597Y536151I-3501J0D01*
G03X59546Y536020I149J-133D01*
G01X59544Y535903D01*
G03X59592Y535770I200J-3D01*
G02X60427Y533500I-2668J-2270D01*
G02X59557Y531190I-3502J0D01*
G03X59508Y531059I151J-131D01*
G01Y530941D01*
G03X59557Y530810I200J0D01*
G02Y526190I-2632J-2310D01*
G03X59508Y526059I151J-131D01*
G01Y525941D01*
G03X59557Y525810I200J0D01*
G02X60427Y523500I-2632J-2310D01*
G02X59557Y521190I-3502J0D01*
G03X59508Y521059I151J-131D01*
G01Y520941D01*
G03X59557Y520810I200J0D01*
G02Y516190I-2632J-2310D01*
G03X59508Y516059I151J-131D01*
G01Y515941D01*
G03X59557Y515810I200J0D01*
G02Y511190I-2632J-2310D01*
G03X59508Y511059I151J-131D01*
G01Y510941D01*
G03X59557Y510810I200J0D01*
G02X60427Y508500I-2632J-2310D01*
G02X59409Y506032I-3501J0D01*
G01X59381Y506003D01*
X59351Y505931D01*
Y505569D01*
X59381Y505497D01*
X59409Y505468D01*
G02X60427Y503000I-2483J-2468D01*
G02X59557Y500690I-3502J0D01*
G03X59508Y500559I151J-131D01*
G01Y500441D01*
G03X59557Y500310I200J0D01*
G02Y495690I-2632J-2310D01*
G03X59508Y495559I151J-131D01*
G01Y495441D01*
G03X59557Y495310I200J0D01*
G02Y490690I-2632J-2310D01*
G03X59508Y490559I151J-131D01*
G01Y490441D01*
G03X59557Y490310I200J0D01*
G02X60427Y488000I-2632J-2310D01*
G02X59592Y485730I-3503J0D01*
G03X59544Y485597I152J-130D01*
G01X59546Y485480D01*
G03X59597Y485349I200J2D01*
G02X60502Y483000I-2596J-2349D01*
G02X53498I-3502J0D01*
G02X54333Y485270I3503J0D01*
G03X54381Y485403I-152J130D01*
G01X54379Y485520D01*
G03X54328Y485651I-200J-2D01*
G02X53423Y488000I2596J2349D01*
G02X54293Y490310I3502J0D01*
G03X54342Y490441I-151J131D01*
G01Y490559D01*
G03X54293Y490690I-200J0D01*
G02Y495310I2632J2310D01*
G03X54342Y495441I-151J131D01*
G01Y495559D01*
G03X54293Y495690I-200J0D01*
G02Y500310I2632J2310D01*
G03X54342Y500441I-151J131D01*
G01Y500559D01*
G03X54293Y500690I-200J0D01*
G02X53423Y503000I2632J2310D01*
G02X54441Y505468I3501J0D01*
G01X54469Y505497D01*
X54499Y505569D01*
Y505931D01*
X54469Y506003D01*
X54441Y506032D01*
G02X53423Y508500I2483J2468D01*
G02X54293Y510810I3502J0D01*
G03X54342Y510941I-151J131D01*
G01Y511059D01*
G03X54293Y511190I-200J0D01*
G02Y515810I2632J2310D01*
G03X54342Y515941I-151J131D01*
G01Y516059D01*
G03X54293Y516190I-200J0D01*
G02Y520810I2632J2310D01*
G03X54342Y520941I-151J131D01*
G01Y521059D01*
G03X54293Y521190I-200J0D01*
G02X53423Y523500I2632J2310D01*
G02X54293Y525810I3502J0D01*
G03X54342Y525941I-151J131D01*
G01Y526059D01*
G03X54293Y526190I-200J0D01*
G02Y530810I2632J2310D01*
G03X54342Y530941I-151J131D01*
G01Y531059D01*
G03X54293Y531190I-200J0D01*
G02X53423Y533500I2632J2310D01*
G02X54328Y535849I3501J0D01*
G03X54379Y535980I-149J133D01*
G37*
G36*
G01X167563Y538396D02*
Y538754D01*
G03X167452Y538934I-200J1D01*
G02X165498Y542075I1548J3141D01*
G02X172502I3502J0D01*
G02X170548Y538934I-3502J0D01*
G03X170437Y538754I89J-179D01*
G01Y538396D01*
G03X170548Y538216I200J-1D01*
G02X172502Y535075I-1548J-3141D01*
G02X170391Y531861I-3502J0D01*
G01X170351Y531844D01*
X170294Y531781D01*
X170174Y531413D01*
X170183Y531328D01*
X170205Y531291D01*
G02X170692Y529510I-3015J-1781D01*
G02X163688I-3502J0D01*
G02X165799Y532724I3502J0D01*
G01X165839Y532741D01*
X165896Y532804D01*
X166016Y533172D01*
X166007Y533257D01*
X165985Y533294D01*
G02X165498Y535075I3015J1781D01*
G02X167452Y538216I3502J0D01*
G03X167563Y538396I-89J179D01*
G37*
G36*
G01X111295Y540686D02*
G02X111502Y539500I-3294J-1186D01*
G02X104498I-3502J0D01*
G02X105651Y542097I3501J0D01*
G03X105705Y542314I-134J149D01*
G02X105498Y543500I3294J1186D01*
G02X112502I3502J0D01*
G02X111349Y540903I-3501J0D01*
G03X111295Y540686I134J-149D01*
G37*
G36*
G01X68745Y540607D02*
X69010Y540901D01*
X69036Y540984D01*
X69030Y541029D01*
G02X68998Y541500I3470J472D01*
G02X71788Y544929I3502J0D01*
G03X71944Y545091I-41J196D01*
G02X75396Y548002I3452J-591D01*
G02X78898Y544500I0J-3502D01*
G02X76108Y541071I-3502J0D01*
G03X75952Y540909I41J-196D01*
G02X72500Y537998I-3452J591D01*
G02X72380Y538000I-2J3502D01*
G01X72335Y538002D01*
X72255Y537968D01*
X71990Y537674D01*
X71964Y537591D01*
X71970Y537546D01*
G02X72002Y537075I-3470J-472D01*
G02X71426Y535151I-3501J0D01*
G03X71418Y534945I167J-110D01*
G02X71847Y533265I-3073J-1680D01*
G02X64843I-3502J0D01*
G02X65419Y535189I3501J0D01*
G03X65427Y535395I-167J110D01*
G02X64998Y537075I3073J1680D01*
G02X68500Y540577I3502J0D01*
G02X68620Y540575I2J-3502D01*
G01X68665Y540573D01*
X68745Y540607D01*
G37*
G36*
G01X82528Y559129D02*
X82591Y559544D01*
X82562Y559634D01*
X82528Y559668D01*
G02X81498Y562148I2471J2480D01*
G02X85000Y565650I3502J0D01*
G02X87710Y564367I1J-3502D01*
G01X87736Y564334D01*
X87809Y564296D01*
X88184Y564271D01*
X88261Y564299D01*
X88292Y564327D01*
G02X90680Y565268I2388J-2561D01*
G02Y558264I0J-3502D01*
G02X87970Y559547I-1J3502D01*
G01X87944Y559580D01*
X87871Y559618D01*
X87496Y559643D01*
X87419Y559615D01*
X87388Y559587D01*
G02X86620Y559043I-2390J2560D01*
G01X86577Y559021D01*
X86522Y558944D01*
X86459Y558529D01*
X86488Y558439D01*
X86522Y558405D01*
G02X87552Y555925I-2471J-2480D01*
G02X80548I-3502J0D01*
G02X82430Y559030I3502J0D01*
G01X82473Y559052D01*
X82528Y559129D01*
G37*
G36*
G01X121283Y560995D02*
G03X121642Y561508I-25J399D01*
G02X121498Y562500I3358J994D01*
G02X128502I3502J0D01*
G02X125217Y559005I-3502J0D01*
G03X124858Y558492I25J-399D01*
G02X125002Y557500I-3358J-994D01*
G02X117998I-3502J0D01*
G02X121283Y560995I3502J0D01*
G37*
G36*
G01X132263Y563835D02*
G02X135500Y566002I3237J-1334D01*
G02X139002Y562500I0J-3502D01*
G02X136837Y559263I-3502J0D01*
G03X136728Y559155I76J-185D01*
G02X133491Y556988I-3237J1334D01*
G02X129989Y560490I0J3502D01*
G02X132154Y563727I3502J0D01*
G03X132263Y563835I-76J185D01*
G37*
G36*
G01X77438Y609090D02*
G02X77502Y608425I-3438J-666D01*
G02X70498I-3502J0D01*
G02X71372Y610740I3503J0D01*
G03X71419Y610910I-150J133D01*
G02X71355Y611575I3438J666D01*
G02X78359I3502J0D01*
G02X77485Y609260I-3503J0D01*
G03X77438Y609090I150J-133D01*
G37*
G36*
G01X106890Y623980D02*
X106520Y623806D01*
X106463Y623734D01*
X106453Y623689D01*
G02X103037Y620960I-3416J773D01*
G02Y627964I0J3502D01*
G02X104615Y627588I-1J-3502D01*
G01X104657Y627567D01*
X104748Y627566D01*
X105118Y627740D01*
X105175Y627812D01*
X105185Y627857D01*
G02X108601Y630586I3416J-773D01*
G02Y623582I0J-3502D01*
G02X107023Y623958I1J3502D01*
G01X106981Y623979D01*
X106890Y623980D01*
G37*
G36*
G01X102645Y633297D02*
X102175Y633334D01*
X102075Y633283D01*
X102045Y633234D01*
G02X99051Y631549I-2994J1817D01*
G02Y638553I0J3502D01*
G02X102294Y636373I0J-3502D01*
G01X102315Y636320D01*
X102406Y636254D01*
X102876Y636217D01*
X102976Y636268D01*
X103006Y636317D01*
G02X106000Y638002I2994J-1817D01*
G02Y630998I0J-3502D01*
G02X102757Y633178I0J3502D01*
G01X102736Y633231D01*
X102645Y633297D01*
G37*
G36*
G01X81686Y635365D02*
G02X81959Y634010I-3229J-1356D01*
G02X74955I-3502J0D01*
G02X75436Y635781I3501J0D01*
G03X75448Y635960I-172J101D01*
G02X75175Y637315I3229J1356D01*
G02X82179I3502J0D01*
G02X81698Y635544I-3501J0D01*
G03X81686Y635365I172J-101D01*
G37*
G36*
G01X131561Y638162D02*
G02X135000Y641002I3439J-662D01*
G02X138502Y637500I0J-3502D01*
G02X135128Y634000I-3502J0D01*
G03X134939Y633838I7J-200D01*
G02X131500Y630998I-3439J662D01*
G02X127998Y634500I0J3502D01*
G02X131372Y638000I3502J0D01*
G03X131561Y638162I-7J200D01*
G37*
G36*
G01X85411Y637580D02*
X85429Y637698D01*
G03X85397Y637841I-197J31D01*
G02X84798Y639800I2904J1959D01*
G02X91802I3502J0D01*
G02X90463Y637046I-3502J0D01*
G03X90389Y636920I124J-157D01*
G01X90371Y636802D01*
G03X90403Y636659I197J-31D01*
G02X91002Y634700I-2904J-1959D01*
G02X83998I-3502J0D01*
G02X85337Y637454I3502J0D01*
G03X85411Y637580I-124J157D01*
G37*
G36*
G01X186050Y640279D02*
X185723Y640155D01*
X185666Y640103D01*
X185650Y640069D01*
G02X182500Y638098I-3150J1532D01*
G02Y645102I0J3502D01*
G02X183838Y644836I-1J-3502D01*
G01X183873Y644822D01*
X183950Y644821D01*
X184277Y644945D01*
X184334Y644997D01*
X184350Y645031D01*
G02X187500Y647002I3150J-1532D01*
G02Y639998I0J-3502D01*
G02X186162Y640264I1J3502D01*
G01X186127Y640278D01*
X186050Y640279D01*
G37*
G36*
G01X33861Y649114D02*
G02X35760Y646000I-1604J-3114D01*
G02X32258Y642498I-3502J0D01*
G02X28879Y645081I0J3502D01*
G03X28777Y645206I-193J-53D01*
G02X26878Y648320I1604J3114D01*
G02X30380Y651822I3502J0D01*
G02X33759Y649239I0J-3502D01*
G03X33861Y649114I193J53D01*
G37*
G36*
G01X44008Y649277D02*
G02X47499Y652502I3491J-277D01*
G02X51001Y649000I0J-3502D01*
G02X49099Y645885I-3502J0D01*
G03X48991Y645723I91J-178D01*
G02X45500Y642498I-3491J277D01*
G02X41998Y646000I0J3502D01*
G02X43900Y649115I3502J0D01*
G03X44008Y649277I-91J178D01*
G37*
G36*
G01X10604Y650008D02*
X10596Y650444D01*
X10548Y650530D01*
X10505Y650557D01*
G02X8887Y653509I1884J2952D01*
G02X15891I3502J0D01*
G02X14384Y650631I-3502J0D01*
G01X14342Y650602D01*
X14297Y650514D01*
X14305Y650078D01*
X14353Y649992D01*
X14396Y649965D01*
G02X16014Y647013I-1884J-2952D01*
G02X14495Y644126I-3503J0D01*
G01X14457Y644100D01*
X14412Y644024D01*
X14379Y643625D01*
X14409Y643542D01*
X14442Y643510D01*
G02X15502Y641000I-2442J-2510D01*
G02X8498I-3502J0D01*
G02X10017Y643887I3503J0D01*
G01X10055Y643913D01*
X10100Y643989D01*
X10133Y644388D01*
X10103Y644471D01*
X10070Y644503D01*
G02X9010Y647013I2442J2510D01*
G02X10517Y649891I3502J0D01*
G01X10559Y649920D01*
X10604Y650008D01*
G37*
G36*
G01X172257Y652944D02*
X172022Y653301D01*
X171937Y653348D01*
X171887Y653349D01*
G02X168475Y656850I90J3501D01*
G02X171977Y660352I3502J0D01*
G02X172417Y660324I-2J-3502D01*
G03X172634Y660467I25J198D01*
G02X176000Y663002I3366J-967D01*
G02Y655998I0J-3502D01*
G02X175560Y656026I2J3502D01*
G03X175343Y655883I-25J-198D01*
G02X175228Y655549I-3364J972D01*
G01X175210Y655503D01*
X175220Y655406D01*
X175455Y655049D01*
X175540Y655002D01*
X175590Y655001D01*
G02X179002Y651500I-90J-3501D01*
G02X171998I-3502J0D01*
G02X172249Y652801I3502J-1D01*
G01X172267Y652847D01*
X172257Y652944D01*
G37*
G36*
G01X35942Y658462D02*
G02X36262Y657000I-3182J-1462D01*
G02X29258I-3502J0D01*
G02X29540Y658376I3502J-1D01*
G03X29538Y658538I-184J79D01*
G02X29218Y660000I3182J1462D01*
G02X36222I3502J0D01*
G02X35940Y658624I-3502J1D01*
G03X35942Y658462I184J-79D01*
G37*
G36*
G01X95199Y663498D02*
G02X98534Y660000I-167J-3498D01*
G02X95032Y656498I-3502J0D01*
G02X91554Y659587I0J3502D01*
G03X91365Y659763I-198J-24D01*
G02X88030Y663261I167J3498D01*
G02X91532Y666763I3502J0D01*
G02X95010Y663674I0J-3502D01*
G03X95199Y663498I198J24D01*
G37*
G36*
G01X189997Y661392D02*
G02X190552Y659500I-2947J-1892D01*
G02X183548I-3502J0D01*
G02X184103Y661392I3502J0D01*
G03Y661608I-168J108D01*
G02X183548Y663500I2947J1892D01*
G02X190552I3502J0D01*
G02X189997Y661608I-3502J0D01*
G03Y661392I168J-108D01*
G37*
G36*
G01X104243Y673374D02*
G02X104786Y671500I-2959J-1873D01*
G02X97782I-3502J0D01*
G02X98349Y673410I3502J0D01*
G03X98350Y673626I-168J109D01*
G02X97807Y675500I2959J1873D01*
G02X104811I3502J0D01*
G02X104244Y673590I-3502J0D01*
G03X104243Y673374I168J-109D01*
G37*
G36*
G01X35945Y680385D02*
G02X36230Y679000I-3217J-1384D01*
G02X29226I-3502J0D01*
G02X29542Y680453I3502J-1D01*
G03X29543Y680615I-182J82D01*
G02X29258Y682000I3217J1384D01*
G02X36262I3502J0D01*
G02X35946Y680547I-3502J1D01*
G03X35945Y680385I182J-82D01*
G37*
G36*
G01X83053Y682108D02*
G02Y685892I2947J1892D01*
G03Y686108I-168J108D01*
G02X82498Y688000I2947J1892D01*
G02X89502I3502J0D01*
G02X88947Y686108I-3502J0D01*
G03Y685892I168J-108D01*
G02Y682108I-2947J-1892D01*
G03Y681892I168J-108D01*
G02Y678108I-2947J-1892D01*
G03Y677892I168J-108D01*
G02X89502Y676000I-2947J-1892D01*
G02X82498I-3502J0D01*
G02X83053Y677892I3502J0D01*
G03Y678108I-168J108D01*
G02Y681892I2947J1892D01*
G03Y682108I-168J108D01*
G37*
G36*
G01X124904Y692215D02*
X125024Y692584D01*
X125014Y692669D01*
X124992Y692707D01*
G02X124498Y694500I3007J1793D01*
G02X128000Y698002I3502J0D01*
G02X131393Y695366I0J-3502D01*
G01X131405Y695321D01*
X131463Y695252D01*
X131833Y695086D01*
X131923Y695088D01*
X131965Y695110D01*
G02X133575Y695502I1610J-3110D01*
G02Y688498I0J-3502D01*
G02X130182Y691134I0J3502D01*
G01X130170Y691179D01*
X130112Y691248D01*
X129742Y691414D01*
X129652Y691412D01*
X129610Y691390D01*
G02X129379Y691281I-1609J3111D01*
G01X129339Y691264D01*
X129281Y691200D01*
X129161Y690831D01*
X129171Y690746D01*
X129193Y690708D01*
G02X129687Y688915I-3007J-1793D01*
G02X122683I-3502J0D01*
G02X124806Y692134I3502J0D01*
G01X124846Y692151D01*
X124904Y692215D01*
G37*
G36*
G01X115644Y692918D02*
X115677Y693324D01*
X115644Y693408D01*
X115610Y693440D01*
G02X114498Y696000I2391J2560D01*
G02X121502I3502J0D01*
G02X119941Y693085I-3502J0D01*
G01X119902Y693059D01*
X119856Y692982D01*
X119823Y692576D01*
X119856Y692492D01*
X119890Y692460D01*
G02X121002Y689900I-2391J-2560D01*
G02X113998I-3502J0D01*
G02X115559Y692815I3502J0D01*
G01X115598Y692841D01*
X115644Y692918D01*
G37*
G36*
G01X179584Y690047D02*
X179347Y690454D01*
X179249Y690506D01*
X179192Y690503D01*
G02X179000Y690498I-187J3497D01*
G02X175498Y694000I0J3502D01*
G02X177480Y697155I3502J0D01*
G03X177588Y697290I-87J180D01*
G02X181000Y700002I3412J-790D01*
G02X184502Y696500I0J-3502D01*
G02X182520Y693345I-3502J0D01*
G03X182412Y693210I87J-180D01*
G02X181949Y692112I-3411J792D01*
G01X181918Y692064D01*
X181916Y691953D01*
X182153Y691546D01*
X182251Y691494D01*
X182308Y691497D01*
G02X182500Y691502I187J-3497D01*
G02X186002Y688000I0J-3502D01*
G02X184104Y684887I-3502J0D01*
G03X183996Y684698I92J-178D01*
G02X184002Y684500I-3496J-205D01*
G02X181150Y681059I-3502J0D01*
G01X181107Y681051D01*
X181038Y681003D01*
X180839Y680671D01*
X180829Y680588D01*
X180842Y680546D01*
G02X181002Y679500I-3342J-1046D01*
G01Y679477D01*
G03X181083Y679315I200J-1D01*
G02X182502Y676500I-2083J-2815D01*
G02X179359Y673016I-3502J0D01*
G01X179321Y673013D01*
X179255Y672978D01*
X179024Y672715D01*
X178999Y672645D01*
X179000Y672606D01*
G02X179002Y672500I-3500J-119D01*
G02X178435Y670590I-3502J0D01*
G03X178434Y670374I168J-109D01*
G02X178977Y668500I-2959J-1873D01*
G02X171973I-3502J0D01*
G02X172540Y670410I3502J0D01*
G03X172541Y670626I-168J109D01*
G02X171998Y672500I2959J1873D01*
G02X175141Y675984I3502J0D01*
G01X175179Y675987D01*
X175245Y676022D01*
X175476Y676285D01*
X175501Y676355D01*
X175500Y676394D01*
G02X175498Y676500I3500J119D01*
G01Y676523D01*
G03X175417Y676685I-200J1D01*
G02X173998Y679500I2083J2815D01*
G02X176850Y682941I3502J0D01*
G01X176893Y682949D01*
X176962Y682997D01*
X177161Y683329D01*
X177171Y683412D01*
X177158Y683454D01*
G02X176998Y684500I3342J1046D01*
G02X178896Y687613I3502J0D01*
G03X179004Y687802I-92J178D01*
G02X178998Y688000I3496J205D01*
G02X179551Y689888I3502J-1D01*
G01X179582Y689936D01*
X179584Y690047D01*
G37*
G36*
G01X88947Y697892D02*
G02X89502Y696000I-2947J-1892D01*
G02X82498I-3502J0D01*
G02X83053Y697892I3502J0D01*
G03Y698108I-168J108D01*
G02X82498Y700000I2947J1892D01*
G02X89502I3502J0D01*
G02X88947Y698108I-3502J0D01*
G03Y697892I168J-108D01*
G37*
G36*
G01X15407Y706456D02*
G02X13000Y705498I-2407J2545D01*
G02X9498Y709000I0J3502D01*
G02X10144Y711027I3503J0D01*
G03X10167Y711216I-163J116D01*
G02X9923Y712500I3258J1284D01*
G02X13425Y716002I3502J0D01*
G02X16801Y713429I0J-3501D01*
G03X16925Y713295I193J54D01*
G02X17239Y713161I-1216J-3284D01*
G03X17488Y713224I87J180D01*
G02X20327Y714676I2839J-2049D01*
G02X23829Y711174I0J-3502D01*
G02X23558Y709823I-3503J0D01*
G03X23565Y709654I184J-77D01*
G02X23955Y708047I-3112J-1606D01*
G02X20453Y704545I-3502J0D01*
G02X17277Y706572I0J3502D01*
G03X17172Y706672I-181J-85D01*
G01X17062Y706718D01*
G03X16917Y706721I-76J-185D01*
G02X15713Y706507I-1205J3288D01*
G02X15553Y706511I7J3502D01*
G03X15407Y706456I-8J-200D01*
G37*
G36*
G01X122258Y712863D02*
X121892Y712896D01*
X121815Y712872D01*
X121784Y712845D01*
G02X119500Y711998I-2284J2656D01*
G02Y719002I0J3502D01*
G02X122220Y717706I0J-3502D01*
G01X122245Y717675D01*
X122317Y717637D01*
X122683Y717604D01*
X122760Y717628D01*
X122791Y717655D01*
G02X125075Y718502I2284J-2656D01*
G02Y711498I0J-3502D01*
G02X122355Y712794I0J3502D01*
G01X122330Y712825D01*
X122258Y712863D01*
G37*
G36*
G01X168081Y716350D02*
G02X168078Y716500I3499J145D01*
G02X168081Y716650I3502J5D01*
G03X167967Y716839I-200J8D01*
G02X165973Y720000I1508J3161D01*
G02X172977I3502J0D01*
G02X172974Y719850I-3502J-5D01*
G03X173088Y719661I200J-8D01*
G02Y713339I-1508J-3161D01*
G03X172974Y713150I86J-181D01*
G02X172977Y713000I-3499J-145D01*
G02X172870Y712143I-3502J2D01*
G03X172977Y711914I194J-49D01*
G02X174942Y708767I-1538J-3147D01*
G02X173048Y705656I-3502J0D01*
G03X172942Y705507I92J-178D01*
G02X169475Y702498I-3467J493D01*
G02X165973Y706000I0J3502D01*
G02X167867Y709111I3502J0D01*
G03X167973Y709260I-92J178D01*
G02X168045Y709624I3466J-497D01*
G03X167938Y709853I-194J49D01*
G02X165973Y713000I1538J3147D01*
G02X167967Y716161I3502J0D01*
G03X168081Y716350I-86J181D01*
G37*
G36*
G01X180038Y716321D02*
Y716679D01*
G03X179927Y716859I-200J1D01*
G02X177973Y720000I1548J3141D01*
G02X184977I3502J0D01*
G02X183023Y716859I-3502J0D01*
G03X182912Y716679I89J-179D01*
G01Y716321D01*
G03X183023Y716141I200J-1D01*
G02X184977Y713000I-1548J-3141D01*
G02X177973I-3502J0D01*
G02X179927Y716141I3502J0D01*
G03X180038Y716321I-89J179D01*
G37*
G36*
G01X188682Y733145D02*
X189052Y733345D01*
X189105Y733423D01*
X189112Y733471D01*
G02X192582Y736502I3470J-471D01*
G02Y729498I0J-3502D01*
G02X191079Y729837I0J3501D01*
G01X191035Y729858D01*
X190941Y729855D01*
X190571Y729655D01*
X190518Y729577D01*
X190511Y729529D01*
G02X190441Y729162I-3470J472D01*
G01X190431Y729120D01*
X190446Y729037D01*
X190661Y728720D01*
X190733Y728675D01*
X190775Y728670D01*
G02X193802Y725200I-475J-3470D01*
G02X186798I-3502J0D01*
G02X186900Y726038I3502J-1D01*
G01X186910Y726080D01*
X186895Y726163D01*
X186680Y726480D01*
X186608Y726525D01*
X186566Y726530D01*
G02X183539Y730000I475J3470D01*
G02X187041Y733502I3502J0D01*
G02X188544Y733163I0J-3501D01*
G01X188588Y733142D01*
X188682Y733145D01*
G37*
G36*
G01X91577Y741258D02*
X91575Y741732D01*
X91515Y741828D01*
X91463Y741853D01*
G02X89498Y745000I1538J3147D01*
G02X96502I3502J0D01*
G02X94559Y741864I-3502J0D01*
G01X94508Y741839D01*
X94448Y741742D01*
X94450Y741268D01*
X94510Y741172D01*
X94562Y741147D01*
G02Y734853I-1538J-3147D01*
G01X94510Y734828D01*
X94450Y734732D01*
X94448Y734258D01*
X94508Y734161D01*
X94559Y734136D01*
G02X96502Y731000I-1559J-3136D01*
G02X89498I-3502J0D01*
G02X91463Y734147I3503J0D01*
G01X91515Y734172D01*
X91575Y734268D01*
X91577Y734742D01*
X91517Y734839D01*
X91466Y734864D01*
G02X89523Y738000I1559J3136D01*
G02X91466Y741136I3502J0D01*
G01X91517Y741161D01*
X91577Y741258D01*
G37*
G36*
G01X180038Y743321D02*
Y743679D01*
G03X179927Y743859I-200J1D01*
G02X177973Y747000I1548J3141D01*
G02X184977I3502J0D01*
G02X183023Y743859I-3502J0D01*
G03X182912Y743679I89J-179D01*
G01Y743321D01*
G03X183023Y743141I200J-1D01*
G02X184593Y741595I-1547J-3142D01*
G03X184752Y741487I178J91D01*
G02X187927Y738000I-327J-3487D01*
G02X184425Y734498I-3502J0D01*
G02X181307Y736405I0J3503D01*
G03X181148Y736513I-178J-91D01*
G02X177973Y740000I327J3487D01*
G02X179927Y743141I3502J0D01*
G03X180038Y743321I-89J179D01*
G37*
G36*
G01X73037Y745748D02*
X72667Y745914D01*
X72577Y745912D01*
X72535Y745890D01*
G02X70925Y745498I-1610J3110D01*
G02Y752502I0J3502D01*
G02X73327Y751548I0J-3501D01*
G01X73359Y751518D01*
X73438Y751491D01*
X73822Y751524D01*
X73896Y751564D01*
X73922Y751599D01*
G02X76725Y753002I2803J-2099D01*
G02X80227Y749500I0J-3502D01*
G02X79809Y747842I-3502J1D01*
G03X79797Y747680I177J-95D01*
G02X80002Y746500I-3297J-1181D01*
G02X79435Y744590I-3502J0D01*
G03X79434Y744374I168J-109D01*
G02X79795Y743613I-2961J-1871D01*
G03X79984Y743477I190J64D01*
G02X83477Y739975I-9J-3502D01*
G02X79975Y736473I-3502J0D01*
G02X76655Y738862I0J3501D01*
G03X76466Y738998I-190J-64D01*
G02X72973Y742500I9J3502D01*
G02X73540Y744410I3502J0D01*
G03X73541Y744626I-168J109D01*
G02X73107Y745634I2960J1872D01*
G01X73095Y745679D01*
X73037Y745748D01*
G37*
G36*
G01X12144Y747653D02*
X11999Y748048D01*
X11928Y748113D01*
X11881Y748126D01*
G02X9317Y751500I938J3374D01*
G02X12819Y755002I3502J0D01*
G02X16309Y751788I0J-3502D01*
G01X16313Y751745D01*
X16354Y751670D01*
X16663Y751439D01*
X16747Y751420D01*
X16789Y751429D01*
G02X17500Y751502I711J-3429D01*
G02X21002Y748000I0J-3502D01*
G02X19048Y744859I-3502J0D01*
G03X18937Y744679I89J-179D01*
G01Y744321D01*
G03X19048Y744141I200J-1D01*
G02X21002Y741000I-1548J-3141D01*
G02X20481Y739162I-3503J0D01*
G03X20479Y738956I170J-105D01*
G02X20960Y737184I-3021J-1771D01*
G02X20639Y735720I-3502J1D01*
G03X20641Y735548I182J-84D01*
G02X21002Y734000I-3141J-1549D01*
G02X17500Y730498I-3502J0D01*
G02X17297Y730504I2J3502D01*
G01X17256Y730506D01*
X17181Y730480D01*
X16909Y730234D01*
X16875Y730163D01*
X16874Y730122D01*
G02X13375Y726772I-3499J152D01*
G02Y733776I0J3502D01*
G02X13578Y733770I-2J-3502D01*
G01X13619Y733768D01*
X13694Y733794D01*
X13966Y734040D01*
X14000Y734111D01*
X14001Y734152D01*
G02X14319Y735464I3499J-153D01*
G03X14317Y735636I-182J84D01*
G02X13956Y737184I3141J1549D01*
G02X14477Y739022I3503J0D01*
G03X14479Y739228I-170J105D01*
G02X13998Y741000I3021J1771D01*
G02X14113Y741889I3502J-1D01*
G03X14095Y742035I-194J50D01*
G01X14038Y742140D01*
G03X13924Y742234I-175J-96D01*
G02X11510Y745563I1088J3329D01*
G02X12106Y747517I3501J0D01*
G01X12133Y747557D01*
X12144Y747653D01*
G37*
G36*
G01X35688Y760147D02*
G02X37000Y760402I1312J-3248D01*
G02Y753398I0J-3502D01*
G02X35474Y753748I0J3502D01*
G03X35312Y753753I-87J-180D01*
G02X34000Y753498I-1312J3248D01*
G02Y760502I0J3502D01*
G02X35526Y760152I0J-3502D01*
G03X35688Y760147I87J180D01*
G37*
G36*
G01X111935Y757814D02*
X112151Y758129D01*
X112166Y758211D01*
X112156Y758253D01*
G02X112061Y759063I3406J810D01*
G02X115563Y762565I3502J0D01*
G02X116168Y762512I-2J-3502D01*
G03X116307Y762538I35J197D01*
G01X116407Y762599D01*
G03X116494Y762710I-104J171D01*
G02X119836Y765166I3342J-1046D01*
G02Y758162I0J-3502D01*
G02X119231Y758215I2J3502D01*
G03X119092Y758189I-35J-197D01*
G01X118992Y758128D01*
G03X118905Y758017I104J-171D01*
G02X116036Y755593I-3342J1046D01*
G01X115994Y755587D01*
X115922Y755543D01*
X115706Y755228D01*
X115691Y755146D01*
X115701Y755104D01*
G02X115796Y754294I-3406J-810D01*
G02X108792I-3502J0D01*
G02X111821Y757764I3502J0D01*
G01X111863Y757770D01*
X111935Y757814D01*
G37*
G36*
G01X15505Y767050D02*
G02X18332Y763614I-675J-3436D01*
G02X14830Y760112I-3502J0D01*
G02X11874Y761736I0J3502D01*
G03X11744Y761825I-169J-107D01*
G02X8917Y765261I675J3436D01*
G02X12419Y768763I3502J0D01*
G02X15375Y767139I0J-3502D01*
G03X15505Y767050I169J107D01*
G37*
G36*
G01X105599Y779087D02*
X105608Y779523D01*
X105563Y779612D01*
X105520Y779641D01*
G02X103998Y782530I1981J2889D01*
G02X111002I3502J0D01*
G02X109358Y779562I-3501J0D01*
G01X109315Y779535D01*
X109266Y779447D01*
X109257Y779011D01*
X109302Y778922D01*
X109345Y778893D01*
G02X110867Y776004I-1981J-2889D01*
G02X103863I-3502J0D01*
G02X105507Y778972I3501J0D01*
G01X105550Y778999D01*
X105599Y779087D01*
G37*
G36*
G01X96834Y784524D02*
X96839Y784641D01*
G03X96794Y784777I-200J9D01*
G02X95998Y787000I2706J2223D01*
G02X103002I3502J0D01*
G02X102002Y784550I-3501J0D01*
G03X101945Y784418I143J-140D01*
G01X101940Y784301D01*
G03X101985Y784165I200J-9D01*
G02X102781Y781942I-2706J-2223D01*
G02X95777I-3502J0D01*
G02X96777Y784392I3501J0D01*
G03X96834Y784524I-143J140D01*
G37*
G36*
G01X139396Y789446D02*
X139601Y789818D01*
X139604Y789916D01*
X139582Y789959D01*
G02X139225Y791500I3145J1540D01*
G02X146229I3502J0D01*
G02X143110Y788019I-3502J0D01*
G01X143062Y788014D01*
X142981Y787959D01*
X142776Y787587D01*
X142773Y787489D01*
X142795Y787446D01*
G02X143152Y785905I-3145J-1540D01*
G02X136148I-3502J0D01*
G02X139267Y789386I3502J0D01*
G01X139315Y789391D01*
X139396Y789446D01*
G37*
G36*
G01X125917Y788941D02*
Y789059D01*
G03X125868Y789190I-200J0D01*
G02X124998Y791500I2632J2310D01*
G02X128500Y795002I3502J0D01*
G02X129136Y794944I1J-3502D01*
G03X129344Y795038I36J197D01*
G02X132350Y796743I3006J-1797D01*
G02X135852Y793241I0J-3502D01*
G02X135187Y791187I-3502J-1D01*
G03X135188Y790951I162J-117D01*
G02X135872Y788872I-2818J-2079D01*
G02X132370Y785370I-3502J0D01*
G02X131985Y785391I-2J3502D01*
G03X131776Y785263I-22J-199D01*
G02X131515Y784718I-3277J1234D01*
G03X131557Y784464I172J-102D01*
G02X132787Y781799I-2272J-2665D01*
G02X132407Y780212I-3502J0D01*
G03X132430Y779996I178J-90D01*
G02X132775Y779482I-2724J-2201D01*
G03X133001Y779385I175J96D01*
G02X133900Y779502I898J-3385D01*
G02Y772498I0J-3502D01*
G02X130830Y774314I0J3503D01*
G03X130604Y774411I-175J-96D01*
G02X129705Y774294I-898J3385D01*
G02X129244Y774324I-4J3502D01*
G01X129189Y774332D01*
X129089Y774289D01*
X128816Y773917D01*
X128805Y773809D01*
X128829Y773759D01*
G02X129156Y772281I-3175J-1478D01*
G02X125654Y768779I-3502J0D01*
G02X122157Y772088I0J3502D01*
G01X122155Y772126D01*
X122124Y772194D01*
X121874Y772436D01*
X121805Y772465D01*
X121766Y772466D01*
G02X118339Y775967I75J3501D01*
G02X121841Y779469I3502J0D01*
G02X125338Y776160I0J-3502D01*
G01X125340Y776122D01*
X125371Y776054D01*
X125621Y775812D01*
X125690Y775783D01*
X125729Y775782D01*
G02X126115Y775753I-69J-3501D01*
G01X126170Y775745D01*
X126270Y775788D01*
X126543Y776160D01*
X126554Y776268D01*
X126530Y776318D01*
G02X126203Y777796I3175J1478D01*
G02X126583Y779383I3502J0D01*
G03X126560Y779599I-178J90D01*
G02X125783Y781799I2726J2200D01*
G02X126270Y783581I3502J0D01*
G03X126228Y783835I-172J102D01*
G02X124998Y786500I2272J2665D01*
G02X125868Y788810I3502J0D01*
G03X125917Y788941I-151J131D01*
G37*
G36*
G01X64053Y804027D02*
X64454Y804265D01*
X64506Y804363D01*
X64503Y804419D01*
G02X64498Y804606I3497J187D01*
G02X68000Y808108I3502J0D01*
G02X68899Y807991I1J-3502D01*
G03X69088Y808039I52J193D01*
G02X71500Y809002I2412J-2539D01*
G02X75002Y805500I0J-3502D01*
G02X72230Y802075I-3502J0D01*
G01X72191Y802067D01*
X72127Y802023D01*
X71929Y801724D01*
X71913Y801648D01*
X71921Y801609D01*
G02X71983Y800951I-3440J-656D01*
G02X68481Y797449I-3502J0D01*
G02X65560Y799019I0J3502D01*
G01X65533Y799060D01*
X65447Y799107D01*
X65018Y799116D01*
X64931Y799072D01*
X64902Y799031D01*
G02X63610Y797935I-2844J2043D01*
G03X63498Y797765I88J-180D01*
G02X60000Y794423I-3498J160D01*
G02X56498Y797925I0J3502D01*
G02X58448Y801065I3503J0D01*
G03X58560Y801235I-88J180D01*
G02X62058Y804577I3498J-160D01*
G02X63894Y804057I0J-3501D01*
G01X63942Y804028D01*
X64053Y804027D01*
G37*
G36*
G01X80833Y806801D02*
Y807199D01*
X80795Y807279D01*
X80761Y807308D01*
G02X79498Y810000I2239J2693D01*
G02X86502I3502J0D01*
G02X85239Y807308I-3502J1D01*
G01X85205Y807279D01*
X85167Y807199D01*
Y806801D01*
X85205Y806721D01*
X85239Y806692D01*
G02X86502Y804000I-2239J-2693D01*
G02X79498I-3502J0D01*
G02X80761Y806692I3502J-1D01*
G01X80795Y806721D01*
X80833Y806801D01*
G37*
G36*
G01X134458Y808014D02*
G02X133246Y807798I-1211J3286D01*
G02X129744Y811300I0J3502D01*
G02X131063Y814039I3503J0D01*
G03X131133Y814245I-124J157D01*
G02X131023Y815114I3392J871D01*
G02X138027I3502J0D01*
G02X136708Y812375I-3503J0D01*
G03X136638Y812169I124J-157D01*
G02X136748Y811300I-3392J-871D01*
G02X136685Y810639I-3502J0D01*
G01X136675Y810586D01*
X136710Y810485D01*
X137059Y810188D01*
X137165Y810170D01*
X137216Y810189D01*
G02X138428Y810405I1211J-3286D01*
G02X141658Y808256I0J-3502D01*
G03X141802Y808137I185J77D01*
G02X144590Y804709I-713J-3428D01*
G02X144238Y803179I-3501J0D01*
G03X144287Y802941I180J-87D01*
G02X145495Y800295I-2294J-2646D01*
G02X141993Y796793I-3502J0D01*
G02X139051Y798395I0J3502D01*
G03X138893Y798487I-169J-108D01*
G02X135573Y801984I182J3497D01*
G02X136192Y803972I3502J0D01*
G03X136157Y804237I-165J113D01*
G02X134926Y806903I2271J2666D01*
G02X134989Y807564I3502J0D01*
G01X134999Y807617D01*
X134964Y807718D01*
X134615Y808015D01*
X134509Y808033D01*
X134458Y808014D01*
G37*
G36*
G01X122835Y817633D02*
X122841Y817751D01*
G03X122796Y817889I-200J11D01*
G02X121998Y820114I2703J2225D01*
G02X129002I3502J0D01*
G02X127952Y817614I-3501J0D01*
G03X127892Y817481I140J-143D01*
G01X127886Y817363D01*
G03X127931Y817225I200J-11D01*
G02X128729Y815000I-2703J-2225D01*
G02X121725I-3502J0D01*
G02X122775Y817500I3501J0D01*
G03X122835Y817633I-140J143D01*
G37*
G36*
G01X90484Y819220D02*
G02X89448Y821707I2467J2487D01*
G02X90645Y824344I3503J0D01*
G03X90702Y824562I-131J151D01*
G02X90498Y825740I3299J1178D01*
G02X97502I3502J0D01*
G02X96305Y823103I-3503J0D01*
G03X96248Y822885I131J-151D01*
G02X96452Y821707I-3299J-1178D01*
G02X96409Y821160I-3501J0D01*
G03X96466Y820987I198J-31D01*
G02X97502Y818500I-2467J-2487D01*
G02X90498I-3502J0D01*
G02X90541Y819047I3501J0D01*
G03X90484Y819220I-198J31D01*
G37*
G36*
G01X64502Y827491D02*
G03X63910Y827810I-399J-31D01*
G02X62216Y827373I-1694J3065D01*
G02Y834377I0J3502D01*
G02X65707Y831148I0J-3502D01*
G03X66299Y830829I399J31D01*
G02X67993Y831266I1694J-3065D01*
G02Y824262I0J-3502D01*
G02X64502Y827491I0J3502D01*
G37*
G36*
G01X22735Y826630D02*
Y826992D01*
X22706Y827064D01*
X22677Y827092D01*
G02X21176Y830748I3702J3656D01*
G02X26378Y835950I5202J0D01*
G02X30034Y834449I0J-5203D01*
G01X30062Y834420D01*
X30134Y834391D01*
X30496D01*
X30568Y834420D01*
X30596Y834449D01*
G02X34252Y835950I3656J-3702D01*
G02X39454Y830748I0J-5202D01*
G02X37953Y827092I-5203J0D01*
G01X37924Y827064D01*
X37895Y826992D01*
Y826630D01*
X37924Y826558D01*
X37953Y826530D01*
G02Y819218I-3702J-3656D01*
G01X37924Y819190D01*
X37895Y819118D01*
Y818756D01*
X37924Y818684D01*
X37953Y818656D01*
G02Y811344I-3702J-3656D01*
G01X37924Y811316D01*
X37895Y811244D01*
Y810882D01*
X37924Y810810D01*
X37953Y810782D01*
G02X39454Y807126I-3702J-3656D01*
G02X38631Y804317I-5202J-1D01*
G01X38601Y804272D01*
X38597Y804163D01*
X38813Y803759D01*
X38906Y803702D01*
X38960Y803701D01*
G02X42402Y800200I-60J-3501D01*
G02X38901Y796698I-3502J0D01*
G01X38845D01*
X38755Y796646D01*
X38727Y796600D01*
G02X37953Y795596I-4476J2650D01*
G01X37924Y795568D01*
X37895Y795496D01*
Y795134D01*
X37924Y795062D01*
X37953Y795034D01*
G02Y787722I-3702J-3656D01*
G01X37924Y787694D01*
X37895Y787622D01*
Y787260D01*
X37924Y787188D01*
X37953Y787160D01*
G02Y779848I-3702J-3656D01*
G01X37924Y779820D01*
X37895Y779748D01*
Y779386D01*
X37924Y779314D01*
X37953Y779286D01*
G02X39454Y775630I-3702J-3656D01*
G02X35216Y770518I-5202J0D01*
G01X35171Y770510D01*
X35099Y770458D01*
X34907Y770108D01*
X34901Y770019D01*
X34918Y769977D01*
G02X25712I-4603J-1827D01*
G01X25729Y770019D01*
X25723Y770108D01*
X25531Y770458D01*
X25459Y770510D01*
X25414Y770518D01*
G02X21176Y775630I964J5112D01*
G02X22677Y779286I5203J0D01*
G01X22706Y779314D01*
X22735Y779386D01*
Y779748D01*
X22706Y779820D01*
X22677Y779848D01*
G02Y787160I3702J3656D01*
G01X22706Y787188D01*
X22735Y787260D01*
Y787622D01*
X22706Y787694D01*
X22677Y787722D01*
G02Y795034I3702J3656D01*
G01X22706Y795062D01*
X22735Y795134D01*
Y795496D01*
X22706Y795568D01*
X22677Y795596D01*
G02Y802908I3702J3656D01*
G01X22706Y802936D01*
X22735Y803008D01*
Y803370D01*
X22706Y803442D01*
X22677Y803470D01*
G02Y810782I3702J3656D01*
G01X22706Y810810D01*
X22735Y810882D01*
Y811244D01*
X22706Y811316D01*
X22677Y811344D01*
G02Y818656I3702J3656D01*
G01X22706Y818684D01*
X22735Y818756D01*
Y819118D01*
X22706Y819190D01*
X22677Y819218D01*
G02Y826530I3702J3656D01*
G01X22706Y826558D01*
X22735Y826630D01*
G37*
G36*
G01X122592Y832635D02*
X122792Y832993D01*
X122796Y833085D01*
X122778Y833128D01*
G02X122498Y834500I3221J1372D01*
G02X129502I3502J0D01*
G02X126529Y831038I-3502J0D01*
G01X126483Y831031D01*
X126408Y830979D01*
X126208Y830621D01*
X126204Y830529D01*
X126222Y830486D01*
G02X126502Y829114I-3221J-1372D01*
G02X119498I-3502J0D01*
G02X122471Y832576I3502J0D01*
G01X122517Y832583D01*
X122592Y832635D01*
G37*
G36*
G01X78480Y833199D02*
X78150Y833409D01*
X78064Y833422D01*
X78022Y833409D01*
G02X77018Y833262I-1004J3355D01*
G02Y840266I0J3502D01*
G02X80485Y837257I0J-3502D01*
G01X80491Y837214D01*
X80538Y837140D01*
X80868Y836930D01*
X80954Y836917D01*
X80996Y836930D01*
G02X82000Y837077I1004J-3355D01*
G02X85502Y833575I0J-3502D01*
G02X83432Y830379I-3502J0D01*
G01X83396Y830363D01*
X83343Y830307D01*
X83211Y829973D01*
X83212Y829896D01*
X83227Y829859D01*
G02X83502Y828500I-3227J-1360D01*
G02X80650Y825059I-3502J0D01*
G01X80607Y825051D01*
X80538Y825003D01*
X80339Y824671D01*
X80329Y824588D01*
X80342Y824546D01*
G02X80502Y823500I-3342J-1046D01*
G02X79781Y821372I-3501J0D01*
G03Y821128I159J-122D01*
G02X80502Y819000I-2780J-2128D01*
G02X77000Y815498I-3502J0D01*
G02X73764Y817662I0J3502D01*
G01X73748Y817701D01*
X73688Y817758D01*
X73335Y817890D01*
X73253Y817886D01*
X73215Y817867D01*
G02X71650Y817498I-1565J3134D01*
G02X69444Y818281I1J3502D01*
G01X69402Y818314D01*
X69298Y818331D01*
X68875Y818174D01*
X68807Y818092D01*
X68798Y818040D01*
G02X65350Y815152I-3448J614D01*
G02X62165Y817198I0J3502D01*
G03X61918Y817304I-182J-83D01*
G02X60773Y817112I-1144J3310D01*
G02Y824116I0J3502D01*
G02X63958Y822070I0J-3502D01*
G03X64205Y821964I182J83D01*
G02X65350Y822156I1144J-3310D01*
G02X67556Y821373I-1J-3502D01*
G01X67598Y821340D01*
X67702Y821323D01*
X68125Y821480D01*
X68193Y821562D01*
X68202Y821614D01*
G02X71650Y824502I3448J-614D01*
G02X73082Y824196I0J-3502D01*
G01X73122Y824178D01*
X73208Y824179D01*
X73563Y824344D01*
X73618Y824409D01*
X73630Y824452D01*
G02X76350Y826941I3370J-952D01*
G01X76393Y826949D01*
X76462Y826997D01*
X76661Y827329D01*
X76671Y827412D01*
X76658Y827454D01*
G02X76498Y828500I3342J1046D01*
G02X78568Y831696I3502J0D01*
G01X78604Y831712D01*
X78657Y831768D01*
X78789Y832102D01*
X78788Y832179D01*
X78773Y832216D01*
G02X78533Y833082I3227J1360D01*
G01X78527Y833125D01*
X78480Y833199D01*
G37*
G36*
G01X168444Y835920D02*
X168636Y836270D01*
X168642Y836359D01*
X168625Y836401D01*
G02X177831I4603J1827D01*
G01X177814Y836359D01*
X177820Y836270D01*
X178012Y835920D01*
X178084Y835868D01*
X178129Y835860D01*
G02X182367Y830748I-964J-5112D01*
G02X180866Y827092I-5203J0D01*
G01X180837Y827064D01*
X180808Y826992D01*
Y826630D01*
X180837Y826558D01*
X180866Y826530D01*
G02Y819218I-3702J-3656D01*
G01X180837Y819190D01*
X180808Y819118D01*
Y818756D01*
X180837Y818684D01*
X180866Y818656D01*
G02Y811344I-3702J-3656D01*
G01X180837Y811316D01*
X180808Y811244D01*
Y810882D01*
X180837Y810810D01*
X180866Y810782D01*
G02Y803470I-3702J-3656D01*
G01X180837Y803442D01*
X180808Y803370D01*
Y803008D01*
X180837Y802936D01*
X180866Y802908D01*
G02Y795596I-3702J-3656D01*
G01X180837Y795568D01*
X180808Y795496D01*
Y795134D01*
X180837Y795062D01*
X180866Y795034D01*
G02Y787722I-3702J-3656D01*
G01X180837Y787694D01*
X180808Y787622D01*
Y787260D01*
X180837Y787188D01*
X180866Y787160D01*
G02Y779848I-3702J-3656D01*
G01X180837Y779820D01*
X180808Y779748D01*
Y779386D01*
X180837Y779314D01*
X180866Y779286D01*
G02X182367Y775630I-3702J-3656D01*
G02X177165Y770428I-5202J0D01*
G02X176870Y770436I-7J5202D01*
G03X176661Y770267I-11J-200D01*
G02X173200Y767298I-3461J533D01*
G02X169739Y770264I0J3502D01*
G03X169532Y770434I-198J-30D01*
G02X169291Y770428I-250J5196D01*
G02X164089Y775630I0J5202D01*
G02X165590Y779286I5203J0D01*
G01X165619Y779314D01*
X165648Y779386D01*
Y779748D01*
X165619Y779820D01*
X165590Y779848D01*
G02Y787160I3702J3656D01*
G01X165619Y787188D01*
X165648Y787260D01*
Y787622D01*
X165619Y787694D01*
X165590Y787722D01*
G02Y795034I3702J3656D01*
G01X165619Y795062D01*
X165648Y795134D01*
Y795496D01*
X165619Y795568D01*
X165590Y795596D01*
G02Y802908I3702J3656D01*
G01X165619Y802936D01*
X165648Y803008D01*
Y803370D01*
X165619Y803442D01*
X165590Y803470D01*
G02Y810782I3702J3656D01*
G01X165619Y810810D01*
X165648Y810882D01*
Y811244D01*
X165619Y811316D01*
X165590Y811344D01*
G02Y818656I3702J3656D01*
G01X165619Y818684D01*
X165648Y818756D01*
Y819118D01*
X165619Y819190D01*
X165590Y819218D01*
G02Y826530I3702J3656D01*
G01X165619Y826558D01*
X165648Y826630D01*
Y826992D01*
X165619Y827064D01*
X165590Y827092D01*
G02X164089Y830748I3702J3656D01*
G02X168327Y835860I5202J0D01*
G01X168372Y835868D01*
X168444Y835920D01*
G37*
G36*
G01X147776Y835356D02*
G02X145600Y834598I-2176J2744D01*
G02X142098Y838100I0J3502D01*
G02X142160Y838758I3502J2D01*
G03X142020Y838988I-196J38D01*
G02X139497Y842350I979J3362D01*
G02X142999Y845852I3502J0D01*
G02X146497Y842512I0J-3502D01*
G01X146500Y842463D01*
X146546Y842381D01*
X146899Y842149D01*
X146993Y842139D01*
X147039Y842156D01*
G02X148281Y842384I1243J-3274D01*
G02Y835380I0J-3502D01*
G02X147921Y835399I4J3502D01*
G03X147776Y835356I-20J-199D01*
G37*
G36*
G01X96417Y850441D02*
Y850559D01*
G03X96368Y850690I-200J0D01*
G02X95498Y853000I2632J2310D01*
G02X102502I3502J0D01*
G02X101632Y850690I-3502J0D01*
G03X101583Y850559I151J-131D01*
G01Y850441D01*
G03X101632Y850310I200J0D01*
G02X102502Y848000I-2632J-2310D01*
G02X95498I-3502J0D01*
G02X96368Y850310I3502J0D01*
G03X96417Y850441I-151J131D01*
G37*
G36*
G01X145976Y850715D02*
X145745Y850978D01*
X145679Y851013D01*
X145641Y851016D01*
G02X142498Y854500I359J3484D01*
G02X146000Y858002I3502J0D01*
G02X147419Y857702I1J-3502D01*
G03X147581I81J182D01*
G02X149000Y858002I1418J-3202D01*
G02X152502Y854500I0J-3502D01*
G02X152151Y852972I-3501J0D01*
G03X152178Y852756I180J-87D01*
G02X153002Y850500I-2678J-2257D01*
G02X145998I-3502J0D01*
G02X146000Y850606I3502J-13D01*
G01X146001Y850645D01*
X145976Y850715D01*
G37*
G36*
G01X9662Y874896D02*
G02X9362Y876315I3202J1418D01*
G02X9662Y877734I3502J1D01*
G03Y877896I-182J81D01*
G02X9362Y879315I3202J1418D01*
G02X12864Y882817I3502J0D01*
G02X14188Y882557I0J-3501D01*
G03X14340I76J185D01*
G02X15664Y882817I1324J-3241D01*
G02X19166Y879315I0J-3502D01*
G02X18866Y877896I-3502J-1D01*
G03Y877734I182J-81D01*
G02X19166Y876315I-3202J-1418D01*
G02X18866Y874896I-3502J-1D01*
G03Y874734I182J-81D01*
G02X19166Y873315I-3202J-1418D01*
G02X18891Y871954I-3502J-1D01*
G03X18887Y871807I184J-79D01*
G02X19102Y870600I-3287J-1208D01*
G02X15600Y867098I-3502J0D01*
G02X14276Y867358I0J3501D01*
G03X14124I-76J-185D01*
G02X12800Y867098I-1324J3241D01*
G02X9298Y870600I0J3502D01*
G02X9573Y871961I3502J1D01*
G03X9577Y872108I-184J79D01*
G02X9362Y873315I3287J1208D01*
G02X9662Y874734I3502J1D01*
G03Y874896I-182J81D01*
G37*
G36*
G01X45106Y878996D02*
G02X44806Y880415I3202J1418D01*
G02X45106Y881834I3502J1D01*
G03Y881996I-182J81D01*
G02X44806Y883415I3202J1418D01*
G02X48308Y886917I3502J0D01*
G02X49490Y886711I-1J-3502D01*
G03X49626I68J189D01*
G02X50808Y886917I1183J-3296D01*
G02X54310Y883415I0J-3502D01*
G02X54010Y881996I-3502J-1D01*
G03Y881834I182J-81D01*
G02X54310Y880415I-3202J-1418D01*
G02X54010Y878996I-3502J-1D01*
G03Y878834I182J-81D01*
G02X54310Y877415I-3202J-1418D01*
G02X50808Y873913I-3502J0D01*
G02X49626Y874119I1J3502D01*
G03X49490I-68J-189D01*
G02X48308Y873913I-1183J3296D01*
G02X44806Y877415I0J3502D01*
G02X45106Y878834I3502J1D01*
G03Y878996I-182J81D01*
G37*
G36*
G01X146662Y891696D02*
G02X146362Y893115I3202J1418D01*
G02X146662Y894534I3502J1D01*
G03Y894696I-182J81D01*
G02X146362Y896115I3202J1418D01*
G02X149864Y899617I3502J0D01*
G02X151046Y899411I-1J-3502D01*
G03X151182I68J189D01*
G02X152364Y899617I1183J-3296D01*
G02X155866Y896115I0J-3502D01*
G02X155566Y894696I-3502J-1D01*
G03Y894534I182J-81D01*
G02X155866Y893115I-3202J-1418D01*
G02X155566Y891696I-3502J-1D01*
G03Y891534I182J-81D01*
G02X155866Y890115I-3202J-1418D01*
G02X152364Y886613I-3502J0D01*
G02X151182Y886819I1J3502D01*
G03X151046I-68J-189D01*
G02X149864Y886613I-1183J3296D01*
G02X146362Y890115I0J3502D01*
G02X146662Y891534I3502J1D01*
G03Y891696I-182J81D01*
G37*
G36*
G01X177062Y894496D02*
G02X176762Y895915I3202J1418D01*
G02X177062Y897334I3502J1D01*
G03Y897496I-182J81D01*
G02X176762Y898915I3202J1418D01*
G02X183766I3502J0D01*
G02X183466Y897496I-3502J-1D01*
G03Y897334I182J-81D01*
G02X183766Y895915I-3202J-1418D01*
G02X183466Y894496I-3502J-1D01*
G03Y894334I182J-81D01*
G02X183766Y892915I-3202J-1418D01*
G02X183466Y891496I-3502J-1D01*
G03Y891334I182J-81D01*
G02X183766Y889915I-3202J-1418D01*
G02X176762I-3502J0D01*
G02X177062Y891334I3502J1D01*
G03Y891496I-182J81D01*
G02X176762Y892915I3202J1418D01*
G02X177062Y894334I3502J1D01*
G03Y894496I-182J81D01*
G37*
G36*
G01X35727Y905660D02*
G02X36027Y904241I-3202J-1418D01*
G02X29023I-3502J0D01*
G02X29323Y905660I3502J1D01*
G03Y905822I-182J81D01*
G02X29023Y907241I3202J1418D01*
G02X36027I3502J0D01*
G02X35727Y905822I-3502J-1D01*
G03Y905660I182J-81D01*
G37*
G36*
G01X14902Y906172D02*
G02X15202Y904753I-3202J-1418D01*
G02X8198I-3502J0D01*
G02X8498Y906172I3502J1D01*
G03Y906334I-182J81D01*
G02X8198Y907753I3202J1418D01*
G02X15202I3502J0D01*
G02X14902Y906334I-3502J-1D01*
G03Y906172I182J-81D01*
G37*
G36*
G01X166079Y911919D02*
G02X166379Y910500I-3202J-1418D01*
G02X159375I-3502J0D01*
G02X159675Y911919I3502J1D01*
G03Y912081I-182J81D01*
G02X159375Y913500I3202J1418D01*
G02X166379I3502J0D01*
G02X166079Y912081I-3502J-1D01*
G03Y911919I182J-81D01*
G37*
G36*
G01X187579D02*
G02X187879Y910500I-3202J-1418D01*
G02X180875I-3502J0D01*
G02X181175Y911919I3502J1D01*
G03Y912081I-182J81D01*
G02X180875Y913500I3202J1418D01*
G02X187879I3502J0D01*
G02X187579Y912081I-3502J-1D01*
G03Y911919I182J-81D01*
G37*
G36*
G01X161329Y928359D02*
G02X159375Y931500I1548J3141D01*
G02X159675Y932919I3502J1D01*
G03Y933081I-182J81D01*
G02X159375Y934500I3202J1418D01*
G02X166379I3502J0D01*
G02X166079Y933081I-3502J-1D01*
G03Y932919I182J-81D01*
G02X166379Y931500I-3202J-1418D01*
G02X164425Y928359I-3502J0D01*
G03X164314Y928179I89J-179D01*
G01Y927821D01*
G03X164425Y927641I200J-1D01*
G02X166379Y924500I-1548J-3141D01*
G02X166079Y923081I-3502J-1D01*
G03Y922919I182J-81D01*
G02X166379Y921500I-3202J-1418D01*
G02X159375I-3502J0D01*
G02X159675Y922919I3502J1D01*
G03Y923081I-182J81D01*
G02X159375Y924500I3202J1418D01*
G02X161329Y927641I3502J0D01*
G03X161440Y927821I-89J179D01*
G01Y928179D01*
G03X161329Y928359I-200J1D01*
G37*
G36*
G01X9427Y931951D02*
G02X8551Y934268I2626J2317D01*
G02X8851Y935687I3502J1D01*
G03Y935849I-182J81D01*
G02X8551Y937268I3202J1418D01*
G02X15555I3502J0D01*
G02X15255Y935849I-3502J-1D01*
G03Y935687I182J-81D01*
G02X15555Y934268I-3202J-1418D01*
G02X14362Y931635I-3502J0D01*
G01X14332Y931609D01*
X14297Y931538D01*
X14274Y931175D01*
X14300Y931100D01*
X14326Y931070D01*
G02X15202Y928753I-2626J-2317D01*
G02X14902Y927334I-3502J-1D01*
G03Y927172I182J-81D01*
G02X15202Y925753I-3202J-1418D01*
G02X13248Y922612I-3502J0D01*
G03X13137Y922432I89J-179D01*
G01Y922074D01*
G03X13248Y921894I200J-1D01*
G02X15202Y918753I-1548J-3141D01*
G02X14902Y917334I-3502J-1D01*
G03Y917172I182J-81D01*
G02X15202Y915753I-3202J-1418D01*
G02X8198I-3502J0D01*
G02X8498Y917172I3502J1D01*
G03Y917334I-182J81D01*
G02X8198Y918753I3202J1418D01*
G02X10152Y921894I3502J0D01*
G03X10263Y922074I-89J179D01*
G01Y922432D01*
G03X10152Y922612I-200J1D01*
G02X8198Y925753I1548J3141D01*
G02X8498Y927172I3502J1D01*
G03Y927334I-182J81D01*
G02X8198Y928753I3202J1418D01*
G02X9391Y931386I3502J0D01*
G01X9421Y931412D01*
X9456Y931483D01*
X9479Y931846D01*
X9453Y931921D01*
X9427Y931951D01*
G37*
G36*
G01X30789Y936234D02*
G02X31089Y934815I-3202J-1418D01*
G02X24085I-3502J0D01*
G02X24385Y936234I3502J1D01*
G03Y936396I-182J81D01*
G02X24085Y937815I3202J1418D01*
G02X31089I3502J0D01*
G02X30789Y936396I-3502J-1D01*
G03Y936234I182J-81D01*
G37*
G36*
G01X171379Y941519D02*
G02X171679Y940100I-3202J-1418D01*
G02X164675I-3502J0D01*
G02X164975Y941519I3502J1D01*
G03Y941681I-182J81D01*
G02X164675Y943100I3202J1418D01*
G02X171679I3502J0D01*
G02X171379Y941681I-3502J-1D01*
G03Y941519I182J-81D01*
G37*
G36*
G01X181389Y937089D02*
G02X179675Y940100I1788J3011D01*
G02X179975Y941519I3502J1D01*
G03Y941681I-182J81D01*
G02X179675Y943100I3202J1418D01*
G02X186679I3502J0D01*
G02X186379Y941681I-3502J-1D01*
G03Y941519I182J-81D01*
G02X186679Y940100I-3202J-1418D01*
G02X186042Y938085I-3502J-1D01*
G01X186017Y938051D01*
X186001Y937970D01*
X186080Y937600D01*
X186128Y937533D01*
X186165Y937511D01*
G02X187879Y934500I-1788J-3011D01*
G02X187579Y933081I-3502J-1D01*
G03Y932919I182J-81D01*
G02X187879Y931500I-3202J-1418D01*
G02X185925Y928359I-3502J0D01*
G03X185814Y928179I89J-179D01*
G01Y927821D01*
G03X185925Y927641I200J-1D01*
G02X187879Y924500I-1548J-3141D01*
G02X187579Y923081I-3502J-1D01*
G03Y922919I182J-81D01*
G02X187879Y921500I-3202J-1418D01*
G02X180875I-3502J0D01*
G02X181175Y922919I3502J1D01*
G03Y923081I-182J81D01*
G02X180875Y924500I3202J1418D01*
G02X182829Y927641I3502J0D01*
G03X182940Y927821I-89J179D01*
G01Y928179D01*
G03X182829Y928359I-200J1D01*
G02X180875Y931500I1548J3141D01*
G02X181175Y932919I3502J1D01*
G03Y933081I-182J81D01*
G02X180875Y934500I3202J1418D01*
G02X181512Y936515I3502J1D01*
G01X181537Y936549D01*
X181553Y936630D01*
X181474Y937000D01*
X181426Y937067D01*
X181389Y937089D01*
G37*
G36*
G01X11291Y957534D02*
G02X11085Y958716I3296J1183D01*
G02X14587Y962218I3502J0D01*
G02X15769Y962012I-1J-3502D01*
G03X15905I68J189D01*
G02X17087Y962218I1183J-3296D01*
G02X18307Y961999I1J-3502D01*
G03X18447I70J187D01*
G02X19667Y962218I1219J-3283D01*
G02X23169Y958716I0J-3502D01*
G02X22963Y957534I-3502J1D01*
G03Y957398I189J-68D01*
G02X23169Y956216I-3296J-1183D01*
G02X19667Y952714I-3502J0D01*
G02X18466Y952927I2J3502D01*
G03X18328I-69J-188D01*
G02X17127Y952714I-1203J3289D01*
G02X15926Y952927I2J3502D01*
G03X15788I-69J-188D01*
G02X14587Y952714I-1203J3289D01*
G02X11085Y956216I0J3502D01*
G02X11291Y957398I3502J-1D01*
G03Y957534I-189J68D01*
G37*
G36*
G01X134982Y960683D02*
G02X134776Y961865I3296J1183D01*
G02X138278Y965367I3502J0D01*
G02X139460Y965161I-1J-3502D01*
G03X139596I68J189D01*
G02X140778Y965367I1183J-3296D01*
G02X141998Y965148I1J-3502D01*
G03X142138I70J187D01*
G02X143358Y965367I1219J-3283D01*
G02X146860Y961865I0J-3502D01*
G02X146654Y960683I-3502J1D01*
G03Y960547I189J-68D01*
G02X146860Y959365I-3296J-1183D01*
G02X143358Y955863I-3502J0D01*
G02X142157Y956076I2J3502D01*
G03X142019I-69J-188D01*
G02X140818Y955863I-1203J3289D01*
G02X139617Y956076I2J3502D01*
G03X139479I-69J-188D01*
G02X138278Y955863I-1203J3289D01*
G02X134776Y959365I0J3502D01*
G02X134982Y960547I3502J-1D01*
G03Y960683I-189J68D01*
G37*
G36*
G01X17760Y977992D02*
G02X21002Y974500I-260J-3492D01*
G02X17500Y970998I-3502J0D01*
G02X14678Y972427I0J3501D01*
G03X14531Y972508I-161J-119D01*
G02X11289Y976000I260J3492D01*
G02X14791Y979502I3502J0D01*
G02X17613Y978073I0J-3501D01*
G03X17760Y977992I161J119D01*
G37*
G36*
G01X35866Y972705D02*
G02X35865Y972800I3501J84D01*
G02X36223Y974342I3502J0D01*
G03X36176Y974579I-180J87D01*
G02X34998Y977199I2325J2620D01*
G02X42002I3502J0D01*
G02X41973Y976753I-3502J4D01*
G01X41968Y976710D01*
X41993Y976628D01*
X42248Y976337D01*
X42326Y976302D01*
X42370D01*
G02X45869Y972800I-3J-3502D01*
G02X42367Y969298I-3502J0D01*
G02X40948Y969598I-1J3502D01*
G03X40786I-81J-182D01*
G02X39367Y969298I-1418J3202D01*
G02X39181Y969303I1J3502D01*
G01X39138Y969305D01*
X39061Y969276D01*
X38790Y969012D01*
X38759Y968935D01*
X38760Y968893D01*
G02X38761Y968798I-3501J-84D01*
G02X35259Y972300I-3502J0D01*
G02X35445Y972295I-1J-3502D01*
G01X35488Y972293D01*
X35565Y972322D01*
X35836Y972586D01*
X35867Y972663D01*
X35866Y972705D01*
G37*
G36*
G01X24362Y972719D02*
G02X23524Y974532I2628J2315D01*
G03X23444Y974665I-198J-28D01*
G02X21998Y977500I2056J2835D01*
G02X25500Y981002I3502J0D01*
G02X27600Y980303I1J-3502D01*
G03X27778Y980271I121J160D01*
G02X28791Y980421I1014J-3352D01*
G02X32293Y976919I0J-3502D01*
G02X30955Y974166I-3501J0D01*
G03X30906Y973907I123J-157D01*
G02X31388Y972134I-3020J-1773D01*
G02X24384I-3502J0D01*
G02X24410Y972563I3502J3D01*
G03X24362Y972719I-198J24D01*
G37*
G36*
G01X140531Y980679D02*
G02X142000Y981002I1469J-3179D01*
G02Y973998I0J-3502D01*
G02X140258Y974462I0J3502D01*
G03X140074Y974470I-100J-173D01*
G02X138605Y974147I-1469J3179D01*
G02Y981151I0J3502D01*
G02X140347Y980687I0J-3502D01*
G03X140531Y980679I100J173D01*
G37*
G36*
G01X157605Y975751D02*
X157720Y976112D01*
X157711Y976194D01*
X157690Y976231D01*
G02X157230Y977966I3042J1735D01*
G02X160732Y981468I3502J0D01*
G02X163613Y979956I0J-3501D01*
G03X163831Y979877I165J114D01*
G02X164758Y980002I927J-3377D01*
G02X166177Y979702I1J-3502D01*
G03X166339I81J182D01*
G02X167758Y980002I1418J-3202D01*
G02Y972998I0J-3502D01*
G02X166339Y973298I-1J3502D01*
G03X166177I-81J-182D01*
G02X164758Y972998I-1418J3202D01*
G02X163052Y973442I1J3502D01*
G01X163001Y973470D01*
X162888Y973464D01*
X162497Y973193D01*
X162453Y973089D01*
X162461Y973032D01*
G02X162502Y972500I-3461J-534D01*
G02X155498I-3502J0D01*
G02X157513Y975670I3501J0D01*
G01X157551Y975689D01*
X157605Y975751D01*
G37*
G36*
G01X148273Y978231D02*
X148362Y978632D01*
X148340Y978721D01*
X148310Y978758D01*
G02X147498Y981000I2689J2242D01*
G02X151000Y984502I3502J0D01*
G02X154416Y981770I0J-3502D01*
G03X154515Y981639I195J45D01*
G02X156325Y978573I-1692J-3066D01*
G02X153331Y975108I-3502J0D01*
G03X153160Y974913I29J-198D01*
G02X149658Y971466I-3502J55D01*
G02X146156Y974968I0J3502D01*
G02X148172Y978139I3502J0D01*
G01X148215Y978159D01*
X148273Y978231D01*
G37*
G36*
G01X180866Y985402D02*
G02X182285Y985702I1418J-3202D01*
G02X183704Y985402I1J-3502D01*
G03X183866I81J182D01*
G02X185285Y985702I1418J-3202D01*
G02X186704Y985402I1J-3502D01*
G03X186866I81J182D01*
G02X188285Y985702I1418J-3202D01*
G02Y978698I0J-3502D01*
G02X186866Y978998I-1J3502D01*
G03X186704I-81J-182D01*
G02X185285Y978698I-1418J3202D01*
G02X183866Y978998I-1J3502D01*
G03X183704I-81J-182D01*
G02X182285Y978698I-1418J3202D01*
G02X180866Y978998I-1J3502D01*
G03X180704I-81J-182D01*
G02X179285Y978698I-1418J3202D01*
G02Y985702I0J3502D01*
G02X180704Y985402I1J-3502D01*
G03X180866I81J182D01*
G37*
G36*
G01X37244Y993070D02*
X37351Y993403D01*
X37346Y993477D01*
X37330Y993512D01*
G02X36998Y995000I3170J1488D01*
G02X44002I3502J0D01*
G02X42216Y991947I-3502J0D01*
G01X42183Y991928D01*
X42136Y991871D01*
X42029Y991538D01*
X42034Y991464D01*
X42050Y991429D01*
G02X42382Y989941I-3170J-1488D01*
G02X35378I-3502J0D01*
G02X37164Y992994I3502J0D01*
G01X37197Y993013D01*
X37244Y993070D01*
G37*
G36*
G01X57948Y999602D02*
G02X59367Y999902I1418J-3202D01*
G02X60786Y999602I1J-3502D01*
G03X60948I81J182D01*
G02X62367Y999902I1418J-3202D01*
G02X63786Y999602I1J-3502D01*
G03X63948I81J182D01*
G02X65367Y999902I1418J-3202D01*
G02Y992898I0J-3502D01*
G02X63948Y993198I-1J3502D01*
G03X63786I-81J-182D01*
G02X62367Y992898I-1418J3202D01*
G02X60948Y993198I-1J3502D01*
G03X60786I-81J-182D01*
G02X59367Y992898I-1418J3202D01*
G02X57948Y993198I-1J3502D01*
G03X57786I-81J-182D01*
G02X56367Y992898I-1418J3202D01*
G02X54997Y993177I0J3503D01*
G01X54959Y993193D01*
X54877D01*
X54534Y993042D01*
X54478Y992982D01*
X54464Y992943D01*
G02X54366Y992696I-3302J1167D01*
G03Y992534I182J-81D01*
G02X54666Y991115I-3202J-1418D01*
G02X54366Y989696I-3502J-1D01*
G03Y989534I182J-81D01*
G02X54666Y988115I-3202J-1418D01*
G02X54366Y986696I-3502J-1D01*
G03Y986534I182J-81D01*
G02X54666Y985115I-3202J-1418D01*
G02X51164Y981613I-3502J0D01*
G02X49982Y981819I1J3502D01*
G03X49846I-68J-189D01*
G02X48664Y981613I-1183J3296D01*
G02X45162Y985115I0J3502D01*
G02X45462Y986534I3502J1D01*
G03Y986696I-182J81D01*
G02X45162Y988115I3202J1418D01*
G02X45462Y989534I3502J1D01*
G03Y989696I-182J81D01*
G02X45162Y991115I3202J1418D01*
G02X45462Y992534I3502J1D01*
G03Y992696I-182J81D01*
G02X45162Y994115I3202J1418D01*
G02X48664Y997617I3502J0D01*
G02X49846Y997411I-1J-3502D01*
G03X49982I68J189D01*
G02X51164Y997617I1183J-3296D01*
G02X52534Y997338I0J-3503D01*
G01X52572Y997322D01*
X52654D01*
X52997Y997473D01*
X53053Y997533D01*
X53067Y997572D01*
G02X56367Y999902I3300J-1172D01*
G02X57786Y999602I1J-3502D01*
G03X57948I81J182D01*
G37*
G36*
G01X165921Y1010931D02*
X166220Y1011304D01*
X166233Y1011419D01*
X166207Y1011471D01*
G02X165856Y1013000I3151J1528D01*
G02X172860I3502J0D01*
G02X170886Y1009849I-3502J0D01*
G03X170780Y1009721I87J-180D01*
G01X170723Y1009513D01*
G02X170735Y1009497I-2794J-2108D01*
G01X170929Y1009459D01*
G03X171073Y1009484I40J196D01*
G02X172905Y1010002I1833J-2984D01*
G02X175066Y1009256I0J-3503D01*
G01X175101Y1009228D01*
X175189Y1009208D01*
X175580Y1009297D01*
X175651Y1009353D01*
X175671Y1009394D01*
G02X178811Y1011345I3140J-1551D01*
G02Y1004341I0J-3502D01*
G02X176650Y1005087I0J3503D01*
G01X176615Y1005115D01*
X176527Y1005135D01*
X176136Y1005046D01*
X176065Y1004990D01*
X176045Y1004949D01*
G02X175979Y1004822I-3140J1551D01*
G01X175955Y1004778D01*
X175954Y1004679D01*
X176151Y1004296D01*
X176232Y1004239D01*
X176281Y1004233D01*
G02X179315Y1001317I-423J-3476D01*
G01X179323Y1001268D01*
X179381Y1001190D01*
X179769Y1001005D01*
X179866Y1001009D01*
X179909Y1001034D01*
G02X181658Y1001502I1749J-3034D01*
G02X183077Y1001202I1J-3502D01*
G03X183239I81J182D01*
G02X184658Y1001502I1418J-3202D01*
G02X186077Y1001202I1J-3502D01*
G03X186239I81J182D01*
G02X187658Y1001502I1418J-3202D01*
G02X188840Y1001296I-1J-3502D01*
G03X188976I68J189D01*
G02X190158Y1001502I1183J-3296D01*
G02X193660Y998000I0J-3502D01*
G02X193360Y996581I-3502J-1D01*
G03Y996419I182J-81D01*
G02X193660Y995000I-3202J-1418D01*
G02X190158Y991498I-3502J0D01*
G02X188976Y991704I1J3502D01*
G03X188840I-68J-189D01*
G02X187658Y991498I-1183J3296D01*
G02X186239Y991798I-1J3502D01*
G03X186077I-81J-182D01*
G02X184658Y991498I-1418J3202D01*
G02X183239Y991798I-1J3502D01*
G03X183077I-81J-182D01*
G02X181658Y991498I-1418J3202D01*
G02X178156Y995000I0J3502D01*
G02X178456Y996419I3502J1D01*
G03Y996581I-182J81D01*
G02X178201Y997440I3202J1418D01*
G01X178193Y997489D01*
X178135Y997567D01*
X177747Y997752D01*
X177650Y997748D01*
X177607Y997723D01*
G02X175858Y997255I-1749J3034D01*
G02X172356Y1000757I0J3502D01*
G02X172784Y1002435I3503J0D01*
G01X172808Y1002479D01*
X172809Y1002578D01*
X172612Y1002961D01*
X172531Y1003018D01*
X172482Y1003024D01*
G02X170378Y1004076I423J3476D01*
G01X170341Y1004114D01*
X170239Y1004144D01*
X169799Y1004040D01*
X169722Y1003967D01*
X169707Y1003916D01*
G02X167847Y1001771I-3349J1025D01*
G03X167737Y1001638I84J-182D01*
G02X167450Y1000871I-3401J835D01*
G03X167464Y1000664I178J-92D01*
G02X168102Y998649I-2863J-2015D01*
G02X165188Y995197I-3502J0D01*
G03X165025Y995036I34J-197D01*
G02X161581Y992171I-3444J638D01*
G02X158675Y993719I0J3502D01*
G01X158649Y993758D01*
X158571Y993803D01*
X158165Y993835D01*
X158081Y993802D01*
X158050Y993768D01*
G02X155482Y992647I-2568J2381D01*
G02Y999651I0J3502D01*
G02X158388Y998103I0J-3502D01*
G01X158414Y998064D01*
X158492Y998019D01*
X158898Y997987D01*
X158982Y998020D01*
X159013Y998054D01*
G02X160993Y999125I2568J-2381D01*
G03X161156Y999286I-34J197D01*
G02X161487Y1000253I3443J-639D01*
G03X161473Y1000460I-178J92D01*
G02X160835Y1002475I2863J2015D01*
G02X162031Y1005111I3503J0D01*
G03X162098Y1005237I-131J151D01*
G01X162112Y1005354D01*
G03X162077Y1005493I-199J24D01*
G02X161445Y1007500I2871J2007D01*
G02X164947Y1011002I3502J0D01*
G02X165755Y1010907I-2J-3502D01*
G01X165812Y1010894D01*
X165921Y1010931D01*
G37*
G36*
G01X18566Y1019002D02*
G02X19985Y1019302I1418J-3202D01*
G02X21404Y1019002I1J-3502D01*
G03X21566I81J182D01*
G02X22985Y1019302I1418J-3202D01*
G02X24404Y1019002I1J-3502D01*
G03X24566I81J182D01*
G02X25985Y1019302I1418J-3202D01*
G02X29487Y1015800I0J-3502D01*
G02X29187Y1014381I-3502J-1D01*
G03Y1014219I182J-81D01*
G02X29487Y1012800I-3202J-1418D01*
G02X25985Y1009298I-3502J0D01*
G02X24566Y1009598I-1J3502D01*
G03X24404I-81J-182D01*
G02X22985Y1009298I-1418J3202D01*
G02X21566Y1009598I-1J3502D01*
G03X21404I-81J-182D01*
G02X19985Y1009298I-1418J3202D01*
G02X18566Y1009598I-1J3502D01*
G03X18404I-81J-182D01*
G02X16985Y1009298I-1418J3202D01*
G02X13483Y1012800I0J3502D01*
G02X13783Y1014219I3502J1D01*
G03Y1014381I-182J81D01*
G02X13483Y1015800I3202J1418D01*
G02X16985Y1019302I3502J0D01*
G02X18404Y1019002I1J-3502D01*
G03X18566I81J182D01*
G37*
G36*
G01X127463Y1019102D02*
G02X128882Y1019402I1418J-3202D01*
G02X130301Y1019102I1J-3502D01*
G03X130463I81J182D01*
G02X131882Y1019402I1418J-3202D01*
G02X133301Y1019102I1J-3502D01*
G03X133463I81J182D01*
G02X134882Y1019402I1418J-3202D01*
G02X138384Y1015900I0J-3502D01*
G02X138084Y1014481I-3502J-1D01*
G03Y1014319I182J-81D01*
G02X138384Y1012900I-3202J-1418D01*
G02X134882Y1009398I-3502J0D01*
G02X133463Y1009698I-1J3502D01*
G03X133301I-81J-182D01*
G02X131882Y1009398I-1418J3202D01*
G02X130463Y1009698I-1J3502D01*
G03X130301I-81J-182D01*
G02X128882Y1009398I-1418J3202D01*
G02X127463Y1009698I-1J3502D01*
G03X127301I-81J-182D01*
G02X125882Y1009398I-1418J3202D01*
G02X122380Y1012900I0J3502D01*
G02X122680Y1014319I3502J1D01*
G03Y1014481I-182J81D01*
G02X122380Y1015900I3202J1418D01*
G02X125882Y1019402I3502J0D01*
G02X127301Y1019102I1J-3502D01*
G03X127463I81J182D01*
G37*
G36*
G01X64780Y1028283D02*
G02X66000Y1028502I1219J-3283D01*
G02Y1021498I0J-3502D01*
G02X63909Y1022190I-1J3502D01*
G03X63720Y1022217I-119J-160D01*
G02X62500Y1021998I-1219J3283D01*
G02Y1029002I0J3502D01*
G02X64591Y1028310I1J-3502D01*
G03X64780Y1028283I119J160D01*
G37*
G36*
G01X171382Y1027976D02*
G02X173858Y1029002I2476J-2475D01*
G02Y1021998I0J-3502D01*
G02X173563Y1022010I-5J3502D01*
G03X173405Y1021953I-17J-199D01*
G02X170929Y1020927I-2476J2475D01*
G02Y1027931I0J3502D01*
G02X171224Y1027919I5J-3502D01*
G03X171382Y1027976I17J199D01*
G37*
G36*
G01X55781Y1023628D02*
G02X56502Y1021500I-2780J-2128D01*
G02X53000Y1017998I-3502J0D01*
G02X50185Y1019417I0J3502D01*
G03X50023Y1019498I-161J-119D01*
G01X50000D01*
G02X46498Y1023000I0J3502D01*
G02X49390Y1026448I3501J0D01*
G03X49552Y1026610I-35J197D01*
G02X53000Y1029502I3448J-609D01*
G02X56502Y1026000I0J-3502D01*
G02X55781Y1023872I-3501J0D01*
G03Y1023628I159J-122D01*
G37*
G36*
G01X165324Y1025071D02*
G02X166002Y1023000I-2824J-2071D01*
G02X162500Y1019498I-3502J0D01*
G02X161081Y1019798I-1J3502D01*
G03X160919I-81J-182D01*
G02X159500Y1019498I-1418J3202D01*
G02X155998Y1023000I0J3502D01*
G02X158276Y1026281I3502J0D01*
G03X158405Y1026446I-70J188D01*
G02X161884Y1029550I3479J-398D01*
G02X165386Y1026048I0J-3502D01*
G02X165291Y1025236I-3502J-2D01*
G03X165324Y1025071I194J-47D01*
G37*
G36*
G01X38053Y1023702D02*
G02X37555Y1023666I-501J3466D01*
G02Y1030670I0J3502D01*
G02X38974Y1030370I1J-3502D01*
G03X39136I81J182D01*
G02X40555Y1030670I1418J-3202D01*
G02X41654Y1030493I0J-3502D01*
G03X41846Y1030530I63J190D01*
G02X44100Y1031352I2254J-2679D01*
G02X47602Y1027850I0J-3502D01*
G02X45522Y1024650I-3502J0D01*
G01X45487Y1024634D01*
X45435Y1024581D01*
X45297Y1024263D01*
X45294Y1024189D01*
X45307Y1024153D01*
G02X45502Y1023000I-3307J-1152D01*
G02X38498I-3502J0D01*
G02X38509Y1023274I3502J-3D01*
G01X38512Y1023320D01*
X38480Y1023404D01*
X38185Y1023681D01*
X38099Y1023708D01*
X38053Y1023702D01*
G37*
G36*
G01X146336Y1024604D02*
X146136Y1024970D01*
X146058Y1025023D01*
X146010Y1025030D01*
G02X142980Y1028500I472J3470D01*
G02X146482Y1032002I3502J0D01*
G02X147901Y1031702I1J-3502D01*
G03X148063I81J182D01*
G02X149482Y1032002I1418J-3202D01*
G02X151275Y1031508I0J-3501D01*
G03X151473Y1031504I103J172D01*
G02X153150Y1031932I1678J-3074D01*
G02Y1024928I0J-3502D01*
G01X153096D01*
X153045Y1024929D01*
X152956Y1024883D01*
X152711Y1024519D01*
X152702Y1024419D01*
X152722Y1024372D01*
G02X153002Y1023000I-3221J-1372D01*
G02X145998I-3502J0D01*
G02X146320Y1024466I3502J-1D01*
G01X146340Y1024510D01*
X146336Y1024604D01*
G37*
G36*
G01X18566Y1032002D02*
G02X19985Y1032302I1418J-3202D01*
G02X21404Y1032002I1J-3502D01*
G03X21566I81J182D01*
G02X22985Y1032302I1418J-3202D01*
G02X24404Y1032002I1J-3502D01*
G03X24566I81J182D01*
G02X25985Y1032302I1418J-3202D01*
G02Y1025298I0J-3502D01*
G02X24566Y1025598I-1J3502D01*
G03X24404I-81J-182D01*
G02X22985Y1025298I-1418J3202D01*
G02X21566Y1025598I-1J3502D01*
G03X21404I-81J-182D01*
G02X19985Y1025298I-1418J3202D01*
G02X18566Y1025598I-1J3502D01*
G03X18404I-81J-182D01*
G02X16985Y1025298I-1418J3202D01*
G02Y1032302I0J3502D01*
G02X18404Y1032002I1J-3502D01*
G03X18566I81J182D01*
G37*
G36*
G01X56889Y1042602D02*
G02X56683Y1043784I3296J1183D01*
G02X60185Y1047286I3502J0D01*
G02X61386Y1047073I-2J-3502D01*
G03X61524I69J188D01*
G02X62725Y1047286I1203J-3289D01*
G02X63926Y1047073I-2J-3502D01*
G03X64064I69J188D01*
G02X65265Y1047286I1203J-3289D01*
G02X68767Y1043784I0J-3502D01*
G02X68561Y1042602I-3502J1D01*
G03Y1042466I189J-68D01*
G02X68767Y1041284I-3296J-1183D01*
G02X65265Y1037782I-3502J0D01*
G02X64083Y1037988I1J3502D01*
G03X63947I-68J-189D01*
G02X62765Y1037782I-1183J3296D01*
G02X61545Y1038001I-1J3502D01*
G03X61405I-70J-187D01*
G02X60185Y1037782I-1219J3283D01*
G02X56683Y1041284I0J3502D01*
G02X56889Y1042466I3502J-1D01*
G03Y1042602I-189J68D01*
G37*
G36*
G01X165686D02*
G02X165480Y1043784I3296J1183D01*
G02X168982Y1047286I3502J0D01*
G02X170183Y1047073I-2J-3502D01*
G03X170321I69J188D01*
G02X171522Y1047286I1203J-3289D01*
G02X172723Y1047073I-2J-3502D01*
G03X172861I69J188D01*
G02X174062Y1047286I1203J-3289D01*
G02X177564Y1043784I0J-3502D01*
G02X177358Y1042602I-3502J1D01*
G03Y1042466I189J-68D01*
G02X177564Y1041284I-3296J-1183D01*
G02X174062Y1037782I-3502J0D01*
G02X172880Y1037988I1J3502D01*
G03X172744I-68J-189D01*
G02X171562Y1037782I-1183J3296D01*
G02X170342Y1038001I-1J3502D01*
G03X170202I-70J-187D01*
G02X168982Y1037782I-1219J3283D01*
G02X165480Y1041284I0J3502D01*
G02X165686Y1042466I3502J-1D01*
G03Y1042602I-189J68D01*
G37*
G36*
G01X18581Y1065922D02*
G02X20000Y1066222I1418J-3202D01*
G02X21419Y1065922I1J-3502D01*
G03X21581I81J182D01*
G02X23000Y1066222I1418J-3202D01*
G02X24419Y1065922I1J-3502D01*
G03X24581I81J182D01*
G02X26000Y1066222I1418J-3202D01*
G02Y1059218I0J-3502D01*
G02X24581Y1059518I-1J3502D01*
G03X24419I-81J-182D01*
G02X23000Y1059218I-1418J3202D01*
G02X21581Y1059518I-1J3502D01*
G03X21419I-81J-182D01*
G02X20000Y1059218I-1418J3202D01*
G02X18581Y1059518I-1J3502D01*
G03X18419I-81J-182D01*
G02X17000Y1059218I-1418J3202D01*
G02X15581Y1059518I-1J3502D01*
G03X15419I-81J-182D01*
G02X14000Y1059218I-1418J3202D01*
G02Y1066222I0J3502D01*
G02X15419Y1065922I1J-3502D01*
G03X15581I81J182D01*
G02X17000Y1066222I1418J-3202D01*
G02X18419Y1065922I1J-3502D01*
G03X18581I81J182D01*
G37*
G36*
G01X182939Y1065966D02*
G02X184358Y1066266I1418J-3202D01*
G02X185777Y1065966I1J-3502D01*
G03X185939I81J182D01*
G02X187358Y1066266I1418J-3202D01*
G02X188777Y1065966I1J-3502D01*
G03X188939I81J182D01*
G02X190358Y1066266I1418J-3202D01*
G02X193860Y1062764I0J-3502D01*
G02X193619Y1061487I-3502J0D01*
G03Y1061341I186J-73D01*
G02X193860Y1060064I-3261J-1277D01*
G02X190358Y1056562I-3502J0D01*
G02X188939Y1056862I-1J3502D01*
G03X188777I-81J-182D01*
G02X187358Y1056562I-1418J3202D01*
G02X185939Y1056862I-1J3502D01*
G03X185777I-81J-182D01*
G02X184358Y1056562I-1418J3202D01*
G02X182939Y1056862I-1J3502D01*
G03X182777I-81J-182D01*
G02X181358Y1056562I-1418J3202D01*
G02X177856Y1060064I0J3502D01*
G02X178097Y1061341I3502J0D01*
G03Y1061487I-186J73D01*
G02X177856Y1062764I3261J1277D01*
G02X181358Y1066266I3502J0D01*
G02X182777Y1065966I1J-3502D01*
G03X182939I81J182D01*
G37*
G36*
G01X117776Y1073818D02*
G02X117570Y1075000I3296J1183D01*
G02X117776Y1076182I3502J-1D01*
G03Y1076318I-189J68D01*
G02X117570Y1077500I3296J1183D01*
G02X124574I3502J0D01*
G02X124368Y1076318I-3502J1D01*
G03Y1076182I189J-68D01*
G02X124574Y1075000I-3296J-1183D01*
G02X124542Y1074528I-3502J0D01*
G01X124534Y1074471D01*
X124579Y1074369D01*
X124964Y1074100D01*
X125075Y1074093D01*
X125125Y1074120D01*
G02X126760Y1074525I1635J-3098D01*
G02X130262Y1071023I0J-3502D01*
G02X129937Y1069549I-3502J-1D01*
G03X129939Y1069377I181J-84D01*
G02X130295Y1067838I-3146J-1538D01*
G02X123291I-3502J0D01*
G02X123616Y1069312I3502J1D01*
G03X123614Y1069484I-181J84D01*
G02X123572Y1069573I3146J1539D01*
G03X123440Y1069684I-182J-82D01*
G01X123321Y1069715D01*
G03X123152Y1069682I-50J-193D01*
G02X121072Y1068998I-2079J2818D01*
G02X117570Y1072500I0J3502D01*
G02X117776Y1073682I3502J-1D01*
G03Y1073818I-189J68D01*
G37*
G36*
G01X139776Y1074318D02*
G02X139570Y1075500I3296J1183D01*
G02X139776Y1076682I3502J-1D01*
G03Y1076818I-189J68D01*
G02X139570Y1078000I3296J1183D01*
G02X146574I3502J0D01*
G02X146368Y1076818I-3502J1D01*
G03Y1076682I189J-68D01*
G02X146574Y1075500I-3296J-1183D01*
G02X146368Y1074318I-3502J1D01*
G03Y1074182I189J-68D01*
G02X146574Y1073000I-3296J-1183D01*
G02X145135Y1070170I-3502J0D01*
G03X145054Y1070030I118J-162D01*
G02X144868Y1069218I-3482J370D01*
G03Y1069082I189J-68D01*
G02X145074Y1067900I-3296J-1183D01*
G02X138070I-3502J0D01*
G02X138276Y1069082I3502J-1D01*
G03Y1069218I-189J68D01*
G02X138070Y1070400I3296J1183D01*
G02X139509Y1073230I3502J0D01*
G03X139590Y1073370I-118J162D01*
G02X139776Y1074182I3482J-370D01*
G03Y1074318I-189J68D01*
G37*
G36*
G01X73275Y1074543D02*
G02X73024Y1075845I3251J1302D01*
G02X73371Y1077365I3503J0D01*
G03X73368Y1077545I-180J87D01*
G02X72962Y1079181I3096J1637D01*
G02X79966I3502J0D01*
G02X79619Y1077661I-3503J0D01*
G03X79622Y1077481I180J-87D01*
G02X80028Y1075845I-3096J-1637D01*
G02X79718Y1074405I-3502J1D01*
G03X79715Y1074249I183J-82D01*
G02X79966Y1072947I-3251J-1302D01*
G02X79619Y1071427I-3503J0D01*
G03X79622Y1071247I180J-87D01*
G02X80028Y1069611I-3096J-1637D01*
G02X78765Y1066918I-3503J0D01*
G01X78735Y1066893D01*
X78699Y1066828D01*
X78656Y1066480D01*
X78674Y1066408D01*
X78697Y1066376D01*
G02X79362Y1064323I-2837J-2053D01*
G02X79037Y1062849I-3502J-1D01*
G03X79039Y1062677I181J-84D01*
G02X79395Y1061138I-3146J-1538D01*
G02X72391I-3502J0D01*
G02X72716Y1062612I3502J1D01*
G03X72714Y1062784I-181J84D01*
G02X72358Y1064323I3146J1538D01*
G02X73621Y1067016I3503J0D01*
G01X73651Y1067041D01*
X73687Y1067106D01*
X73730Y1067454D01*
X73712Y1067526D01*
X73689Y1067558D01*
G02X73024Y1069611I2837J2053D01*
G02X73371Y1071131I3503J0D01*
G03X73368Y1071311I-180J87D01*
G02X72962Y1072947I3096J1637D01*
G02X73272Y1074387I3502J-1D01*
G03X73275Y1074543I-183J82D01*
G37*
G36*
G01X52759Y1073977D02*
G02X52198Y1075878I2940J1901D01*
G02X52592Y1077491I3502J-1D01*
G03Y1077676I-178J92D01*
G02X52198Y1079289I3108J1614D01*
G02X59202I3502J0D01*
G02X58808Y1077676I-3502J1D01*
G03Y1077491I178J-93D01*
G02X59202Y1075878I-3108J-1614D01*
G02X58642Y1073978I-3503J0D01*
G03Y1073761I168J-109D01*
G02X59203Y1071860I-2940J-1901D01*
G02X58809Y1070247I-3502J1D01*
G03Y1070062I178J-93D01*
G02X59203Y1068449I-3108J-1614D01*
G02X59148Y1067831I-3502J0D01*
G01X59138Y1067776D01*
X59176Y1067675D01*
X59536Y1067385D01*
X59643Y1067369D01*
X59694Y1067391D01*
G02X61029Y1067655I1334J-3238D01*
G02X64531Y1064153I0J-3502D01*
G02X64137Y1062540I-3502J1D01*
G03Y1062355I178J-92D01*
G02X64531Y1060742I-3108J-1614D01*
G02X57527I-3502J0D01*
G02X57921Y1062355I3502J-1D01*
G03Y1062540I-178J93D01*
G02X57527Y1064153I3108J1614D01*
G02X57582Y1064771I3502J0D01*
G01X57592Y1064826D01*
X57554Y1064927D01*
X57194Y1065217D01*
X57087Y1065233D01*
X57036Y1065211D01*
G02X55701Y1064947I-1334J3238D01*
G02X52199Y1068449I0J3502D01*
G02X52593Y1070062I3502J-1D01*
G03Y1070247I-178J92D01*
G02X52199Y1071860I3108J1614D01*
G02X52759Y1073760I3503J0D01*
G03Y1073977I-168J108D01*
G37*
G36*
G01X58743Y1092278D02*
G02X59137Y1090665I-3108J-1614D01*
G02X52133I-3502J0D01*
G02X52527Y1092278I3502J-1D01*
G03Y1092463I-178J92D01*
G02X52133Y1094076I3108J1614D01*
G02X59137I3502J0D01*
G02X58743Y1092463I-3502J1D01*
G03Y1092278I178J-92D01*
G37*
G36*
G01X79589Y1092865D02*
G02X79995Y1091229I-3096J-1637D01*
G02X72991I-3502J0D01*
G02X73338Y1092749I3503J0D01*
G03X73335Y1092929I-180J87D01*
G02X72929Y1094565I3096J1637D01*
G02X79933I3502J0D01*
G02X79586Y1093045I-3503J0D01*
G03X79589Y1092865I180J-87D01*
G37*
G36*
G01X117776Y1093318D02*
G02X117570Y1094500I3296J1183D01*
G02X117776Y1095682I3502J-1D01*
G03Y1095818I-189J68D01*
G02X117570Y1097000I3296J1183D01*
G02X124574I3502J0D01*
G02X124368Y1095818I-3502J1D01*
G03Y1095682I189J-68D01*
G02X124574Y1094500I-3296J-1183D01*
G02X124368Y1093318I-3502J1D01*
G03Y1093182I189J-68D01*
G02X124574Y1092000I-3296J-1183D01*
G02X117570I-3502J0D01*
G02X117776Y1093182I3502J-1D01*
G03Y1093318I-189J68D01*
G37*
G36*
G01X139776Y1093818D02*
G02X139570Y1095000I3296J1183D01*
G02X139776Y1096182I3502J-1D01*
G03Y1096318I-189J68D01*
G02X139570Y1097500I3296J1183D01*
G02X146574I3502J0D01*
G02X146368Y1096318I-3502J1D01*
G03Y1096182I189J-68D01*
G02X146574Y1095000I-3296J-1183D01*
G02X146368Y1093818I-3502J1D01*
G03Y1093682I189J-68D01*
G02X146574Y1092500I-3296J-1183D01*
G02X139570I-3502J0D01*
G02X139776Y1093682I3502J-1D01*
G03Y1093818I-189J68D01*
G37*
G36*
G01X177256Y1105243D02*
G02X176956Y1106662I3202J1418D01*
G02X180458Y1110164I3502J0D01*
G02X181877Y1109864I1J-3502D01*
G03X182039I81J182D01*
G02X183458Y1110164I1418J-3202D01*
G02X184877Y1109864I1J-3502D01*
G03X185039I81J182D01*
G02X186458Y1110164I1418J-3202D01*
G02X189960Y1106662I0J-3502D01*
G02X189660Y1105243I-3502J-1D01*
G03Y1105081I182J-81D01*
G02X189960Y1103662I-3202J-1418D01*
G02X186458Y1100160I-3502J0D01*
G02X185039Y1100460I-1J3502D01*
G03X184877I-81J-182D01*
G02X183458Y1100160I-1418J3202D01*
G02X182039Y1100460I-1J3502D01*
G03X181877I-81J-182D01*
G02X180458Y1100160I-1418J3202D01*
G02X176956Y1103662I0J3502D01*
G02X177256Y1105081I3502J1D01*
G03Y1105243I-182J81D01*
G37*
G36*
G01X15798Y1105881D02*
G02X15498Y1107300I3202J1418D01*
G02X19000Y1110802I3502J0D01*
G02X20419Y1110502I1J-3502D01*
G03X20581I81J182D01*
G02X22000Y1110802I1418J-3202D01*
G02X23419Y1110502I1J-3502D01*
G03X23581I81J182D01*
G02X25000Y1110802I1418J-3202D01*
G02X28502Y1107300I0J-3502D01*
G02X28202Y1105881I-3502J-1D01*
G03Y1105719I182J-81D01*
G02X28502Y1104300I-3202J-1418D01*
G02X25000Y1100798I-3502J0D01*
G02X23581Y1101098I-1J3502D01*
G03X23419I-81J-182D01*
G02X22000Y1100798I-1418J3202D01*
G02X20581Y1101098I-1J3502D01*
G03X20419I-81J-182D01*
G02X19000Y1100798I-1418J3202D01*
G02X15498Y1104300I0J3502D01*
G02X15798Y1105719I3502J1D01*
G03Y1105881I-182J81D01*
G37*
G36*
G01X65680Y1138103D02*
X65247Y1138100D01*
X65160Y1138053D01*
X65132Y1138011D01*
G02X62216Y1136448I-2916J1939D01*
G02Y1143452I0J3502D01*
G02X65106Y1141927I0J-3501D01*
G01X65135Y1141886D01*
X65222Y1141840D01*
X65655Y1141843D01*
X65742Y1141890D01*
X65770Y1141932D01*
G02X68686Y1143495I2916J-1939D01*
G02Y1136491I0J-3502D01*
G02X65796Y1138016I0J3501D01*
G01X65767Y1138057D01*
X65680Y1138103D01*
G37*
G36*
G01X74618Y1140687D02*
G02X74016Y1142650I2899J1963D01*
G02X74999Y1145083I3502J0D01*
G03X75013Y1145345I-144J139D01*
G02X74271Y1147500I2760J2155D01*
G02X81275I3502J0D01*
G02X80292Y1145067I-3502J0D01*
G03X80278Y1144805I144J-139D01*
G02X81020Y1142650I-2760J-2155D01*
G02X80418Y1140687I-3501J0D01*
G03Y1140463I166J-112D01*
G02X81020Y1138500I-2899J-1963D01*
G02X80852Y1137427I-3502J-1D01*
G03X80959Y1137184I190J-61D01*
G02X83002Y1134000I-1460J-3184D01*
G02X81067Y1130868I-3502J0D01*
G01X81030Y1130850D01*
X80978Y1130788D01*
X80867Y1130436D01*
X80875Y1130356D01*
X80894Y1130320D01*
G02X81318Y1128650I-3077J-1670D01*
G02X74314I-3502J0D01*
G02X76249Y1131782I3502J0D01*
G01X76286Y1131800D01*
X76338Y1131862D01*
X76449Y1132214D01*
X76441Y1132294D01*
X76422Y1132330D01*
G02X75998Y1134000I3077J1670D01*
G02X76166Y1135073I3502J1D01*
G03X76059Y1135316I-190J61D01*
G02X74016Y1138500I1460J3184D01*
G02X74618Y1140463I3501J0D01*
G03Y1140687I-166J112D01*
G37*
G36*
G01X135557Y1147001D02*
X135769Y1147409D01*
X135763Y1147517D01*
X135733Y1147563D01*
G02X135148Y1149500I2917J1938D01*
G02X138650Y1153002I3502J0D01*
G02X139599Y1152871I0J-3503D01*
G03X139819Y1152952I54J192D01*
G02X142727Y1154502I2908J-1953D01*
G02Y1147498I0J-3502D01*
G02X141778Y1147629I0J3503D01*
G03X141558Y1147548I-54J-192D01*
G02X138740Y1145999I-2908J1952D01*
G01X138685Y1145998D01*
X138593Y1145940D01*
X138381Y1145532D01*
X138387Y1145424D01*
X138417Y1145378D01*
G02X138853Y1144451I-2917J-1938D01*
G01X138867Y1144404D01*
X138937Y1144333D01*
X139347Y1144204D01*
X139444Y1144221D01*
X139483Y1144252D01*
G02X141649Y1145002I2166J-2753D01*
G02Y1137998I0J-3502D01*
G02X139900Y1138466I0J3502D01*
G01X139853Y1138493D01*
X139744Y1138492D01*
X139351Y1138257D01*
X139299Y1138162D01*
X139300Y1138107D01*
G02X139302Y1138000I-3500J-119D01*
G02X132298I-3502J0D01*
G02X133162Y1140304I3502J1D01*
G01X133188Y1140333D01*
X133214Y1140407D01*
X133194Y1140764D01*
X133161Y1140835D01*
X133132Y1140861D01*
G02X131998Y1143441I2368J2580D01*
G02X135410Y1146942I3502J0D01*
G01X135465Y1146943D01*
X135557Y1147001D01*
G37*
G36*
G01X129718Y1154385D02*
X129367Y1154404D01*
X129295Y1154380D01*
X129266Y1154355D01*
G02X127000Y1153523I-2266J2670D01*
G02Y1160527I0J3502D01*
G02X129536Y1159440I0J-3502D01*
G01X129562Y1159412D01*
X129632Y1159381D01*
X129983Y1159362D01*
X130055Y1159386D01*
X130084Y1159411D01*
G02X132350Y1160243I2266J-2670D01*
G02Y1153239I0J-3502D01*
G02X129814Y1154326I0J3502D01*
G01X129788Y1154354D01*
X129718Y1154385D01*
G37*
G36*
G01X61073Y1163520D02*
X61268Y1163886D01*
X61270Y1163979D01*
X61250Y1164022D01*
G02X60923Y1165500I3175J1478D01*
G02X64425Y1169002I3502J0D01*
G02X67443Y1167277I0J-3503D01*
G03X67615Y1167178I173J101D01*
G01X67960D01*
G03X68132Y1167277I-1J200D01*
G02X71150Y1169002I3018J-1778D01*
G02X74526Y1166432I0J-3502D01*
G01X74537Y1166390D01*
X74593Y1166323D01*
X74947Y1166157D01*
X75034Y1166156D01*
X75074Y1166174D01*
G02X76500Y1166477I1425J-3199D01*
G02X80002Y1162975I0J-3502D01*
G02X79620Y1161385I-3502J0D01*
G01X79599Y1161344D01*
X79597Y1161253D01*
X79763Y1160885D01*
X79832Y1160827D01*
X79876Y1160816D01*
G02X82502Y1157425I-876J-3391D01*
G02X75498I-3502J0D01*
G02X75880Y1159015I3502J0D01*
G01X75901Y1159056D01*
X75903Y1159147D01*
X75737Y1159515D01*
X75668Y1159573D01*
X75624Y1159584D01*
G02X73124Y1162043I876J3391D01*
G01X73113Y1162085D01*
X73057Y1162152D01*
X72703Y1162318D01*
X72616Y1162319D01*
X72576Y1162301D01*
G02X71150Y1161998I-1425J3199D01*
G02X68132Y1163723I0J3503D01*
G03X67960Y1163822I-173J-101D01*
G01X67615D01*
G03X67443Y1163723I1J-200D01*
G02X64975Y1162041I-3018J1777D01*
G01X64928Y1162034D01*
X64852Y1161980D01*
X64657Y1161614D01*
X64655Y1161521D01*
X64675Y1161478D01*
G02X65002Y1160000I-3175J-1478D01*
G02X57998I-3502J0D01*
G02X60950Y1163459I3503J0D01*
G01X60997Y1163466D01*
X61073Y1163520D01*
G37*
G36*
G01X138999Y1161588D02*
G03X138604Y1161998I-400J10D01*
G02X135148Y1165500I46J3502D01*
G02X142152I3502J0D01*
G02X142151Y1165412I-3502J-4D01*
G03X142546Y1165002I400J-10D01*
G02X146002Y1161500I-46J-3502D01*
G02X138998I-3502J0D01*
G02X138999Y1161588I3502J4D01*
G37*
G36*
G01X75883Y1175205D02*
X75699Y1175281D01*
G03X75551Y1175283I-77J-185D01*
G02X74313Y1175057I-1238J3276D01*
G02Y1182061I0J3502D01*
G02X77504Y1180001I0J-3501D01*
G03X77610Y1179899I182J83D01*
G01X77720Y1179853D01*
G03X77868Y1179851I77J185D01*
G02X79106Y1180077I1238J-3276D01*
G02X82200Y1178216I0J-3502D01*
G03X82376Y1178110I176J94D01*
G01X82730D01*
G03X82906Y1178216I0J200D01*
G02X86000Y1180077I3094J-1641D01*
G02X89463Y1177097I0J-3502D01*
G01X89470Y1177053D01*
X89516Y1176981D01*
X89848Y1176772D01*
X89933Y1176761D01*
X89975Y1176774D01*
G02X91000Y1176927I1024J-3349D01*
G02X92375Y1176646I1J-3502D01*
G03X92577Y1176672I79J184D01*
G02X94730Y1177412I2153J-2762D01*
G02Y1170408I0J-3502D01*
G02X93355Y1170689I-1J3502D01*
G03X93153Y1170663I-79J-184D01*
G02X91000Y1169923I-2153J2762D01*
G02X87537Y1172903I0J3502D01*
G01X87530Y1172947D01*
X87484Y1173019D01*
X87152Y1173228D01*
X87067Y1173239D01*
X87025Y1173226D01*
G02X86000Y1173073I-1024J3349D01*
G02X82789Y1175178I0J3502D01*
G03X82605Y1175298I-183J-80D01*
G01X82501D01*
G03X82317Y1175178I-1J-200D01*
G02X82223Y1174979I-3212J1395D01*
G03X82217Y1174808I178J-92D01*
G02X82502Y1173425I-3217J-1384D01*
G02X75498I-3502J0D01*
G02X75883Y1175021I3502J0D01*
G03X75889Y1175192I-178J92D01*
G02X75883Y1175205I3177J1474D01*
G37*
G36*
G01X122766Y1184533D02*
X122989Y1184862D01*
X123003Y1184948D01*
X122991Y1184991D01*
G02X122858Y1185947I3369J956D01*
G02X129862I3502J0D01*
G02X126713Y1182463I-3502J0D01*
G01X126668Y1182458D01*
X126594Y1182414D01*
X126371Y1182085D01*
X126357Y1181999D01*
X126369Y1181956D01*
G02X126502Y1181000I-3369J-956D01*
G02X126293Y1179809I-3502J1D01*
G01X126279Y1179770D01*
X126283Y1179691D01*
X126445Y1179359D01*
X126504Y1179307D01*
X126543Y1179294D01*
G02X128942Y1175970I-1103J-3324D01*
G02X121938I-3502J0D01*
G02X122147Y1177161I3502J-1D01*
G01X122161Y1177200D01*
X122157Y1177279D01*
X121995Y1177611D01*
X121936Y1177663D01*
X121897Y1177676D01*
G02X119498Y1181000I1103J3324D01*
G02X122647Y1184484I3502J0D01*
G01X122692Y1184489D01*
X122766Y1184533D01*
G37*
G36*
G01X22735Y1190016D02*
Y1190378D01*
X22706Y1190450D01*
X22677Y1190478D01*
G02X21176Y1194134I3702J3656D01*
G02X26378Y1199336I5202J0D01*
G02X30034Y1197835I0J-5203D01*
G01X30062Y1197806D01*
X30134Y1197777D01*
X30496D01*
X30568Y1197806D01*
X30596Y1197835D01*
G02X34252Y1199336I3656J-3702D01*
G02X39454Y1194134I0J-5202D01*
G02X37953Y1190478I-5203J0D01*
G01X37924Y1190450D01*
X37895Y1190378D01*
Y1190016D01*
X37924Y1189944D01*
X37953Y1189916D01*
G02Y1182604I-3702J-3656D01*
G01X37924Y1182576D01*
X37895Y1182504D01*
Y1182142D01*
X37924Y1182070D01*
X37953Y1182042D01*
G02Y1174730I-3702J-3656D01*
G01X37924Y1174702D01*
X37895Y1174630D01*
Y1174268D01*
X37924Y1174196D01*
X37953Y1174168D01*
G02X39454Y1170512I-3702J-3656D01*
G02X38709Y1167829I-5202J0D01*
G01X38676Y1167774D01*
X38686Y1167646D01*
X39016Y1167259D01*
X39140Y1167228D01*
X39200Y1167252D01*
G02X40500Y1167502I1299J-3252D01*
G02Y1160498I0J-3502D01*
G02X39365Y1160687I0J3503D01*
G03X39220Y1160682I-66J-189D01*
G01X39112Y1160635D01*
G03X39009Y1160532I80J-183D01*
G02X37953Y1158982I-4757J2106D01*
G01X37924Y1158954D01*
X37895Y1158882D01*
Y1158520D01*
X37924Y1158448D01*
X37953Y1158420D01*
G02Y1151108I-3702J-3656D01*
G01X37924Y1151080D01*
X37895Y1151008D01*
Y1150646D01*
X37924Y1150574D01*
X37953Y1150546D01*
G02Y1143234I-3702J-3656D01*
G01X37924Y1143206D01*
X37895Y1143134D01*
Y1142772D01*
X37924Y1142700D01*
X37953Y1142672D01*
G02X39454Y1139016I-3702J-3656D01*
G02X35216Y1133904I-5202J0D01*
G01X35171Y1133896D01*
X35099Y1133844D01*
X34907Y1133494D01*
X34901Y1133405D01*
X34918Y1133363D01*
G02X25712I-4603J-1827D01*
G01X25729Y1133405D01*
X25723Y1133494D01*
X25531Y1133844D01*
X25459Y1133896D01*
X25414Y1133904D01*
G02X21176Y1139016I964J5112D01*
G02X22677Y1142672I5203J0D01*
G01X22706Y1142700D01*
X22735Y1142772D01*
Y1143134D01*
X22706Y1143206D01*
X22677Y1143234D01*
G02Y1150546I3702J3656D01*
G01X22706Y1150574D01*
X22735Y1150646D01*
Y1151008D01*
X22706Y1151080D01*
X22677Y1151108D01*
G02Y1158420I3702J3656D01*
G01X22706Y1158448D01*
X22735Y1158520D01*
Y1158882D01*
X22706Y1158954D01*
X22677Y1158982D01*
G02Y1166294I3702J3656D01*
G01X22706Y1166322D01*
X22735Y1166394D01*
Y1166756D01*
X22706Y1166828D01*
X22677Y1166856D01*
G02Y1174168I3702J3656D01*
G01X22706Y1174196D01*
X22735Y1174268D01*
Y1174630D01*
X22706Y1174702D01*
X22677Y1174730D01*
G02Y1182042I3702J3656D01*
G01X22706Y1182070D01*
X22735Y1182142D01*
Y1182504D01*
X22706Y1182576D01*
X22677Y1182604D01*
G02Y1189916I3702J3656D01*
G01X22706Y1189944D01*
X22735Y1190016D01*
G37*
G36*
G01X138568Y1197823D02*
G02X140302Y1194800I-1768J-3023D01*
G02X136800Y1191298I-3502J0D01*
G02X133330Y1194331I0J3501D01*
G03X133232Y1194477I-198J-27D01*
G02X131498Y1197500I1768J3023D01*
G02X135000Y1201002I3502J0D01*
G02X138470Y1197969I0J-3501D01*
G03X138568Y1197823I198J27D01*
G37*
G36*
G01X168444Y1199306D02*
X168636Y1199656D01*
X168642Y1199745D01*
X168625Y1199787D01*
G02X177831I4603J1827D01*
G01X177814Y1199745D01*
X177820Y1199656D01*
X178012Y1199306D01*
X178084Y1199254D01*
X178129Y1199246D01*
G02X182367Y1194134I-964J-5112D01*
G02X180866Y1190478I-5203J0D01*
G01X180837Y1190450D01*
X180808Y1190378D01*
Y1190016D01*
X180837Y1189944D01*
X180866Y1189916D01*
G02Y1182604I-3702J-3656D01*
G01X180837Y1182576D01*
X180808Y1182504D01*
Y1182142D01*
X180837Y1182070D01*
X180866Y1182042D01*
G02Y1174730I-3702J-3656D01*
G01X180837Y1174702D01*
X180808Y1174630D01*
Y1174268D01*
X180837Y1174196D01*
X180866Y1174168D01*
G02Y1166856I-3702J-3656D01*
G01X180837Y1166828D01*
X180808Y1166756D01*
Y1166394D01*
X180837Y1166322D01*
X180866Y1166294D01*
G02Y1158982I-3702J-3656D01*
G01X180837Y1158954D01*
X180808Y1158882D01*
Y1158520D01*
X180837Y1158448D01*
X180866Y1158420D01*
G02Y1151108I-3702J-3656D01*
G01X180837Y1151080D01*
X180808Y1151008D01*
Y1150646D01*
X180837Y1150574D01*
X180866Y1150546D01*
G02Y1143234I-3702J-3656D01*
G01X180837Y1143206D01*
X180808Y1143134D01*
Y1142772D01*
X180837Y1142700D01*
X180866Y1142672D01*
G02X182367Y1139016I-3702J-3656D01*
G02X177165Y1133814I-5202J0D01*
G02X173509Y1135315I0J5203D01*
G01X173481Y1135344D01*
X173409Y1135373D01*
X173047D01*
X172975Y1135344D01*
X172947Y1135315D01*
G02X169291Y1133814I-3656J3702D01*
G02X164089Y1139016I0J5202D01*
G02X165590Y1142672I5203J0D01*
G01X165619Y1142700D01*
X165648Y1142772D01*
Y1143134D01*
X165619Y1143206D01*
X165590Y1143234D01*
G02Y1150546I3702J3656D01*
G01X165619Y1150574D01*
X165648Y1150646D01*
Y1151008D01*
X165619Y1151080D01*
X165590Y1151108D01*
G02Y1158420I3702J3656D01*
G01X165619Y1158448D01*
X165648Y1158520D01*
Y1158882D01*
X165619Y1158954D01*
X165590Y1158982D01*
G02Y1166294I3702J3656D01*
G01X165619Y1166322D01*
X165648Y1166394D01*
Y1166756D01*
X165619Y1166828D01*
X165590Y1166856D01*
G02X164767Y1167944I3702J3655D01*
G03X164561Y1168043I-174J-98D01*
G02X164000Y1167998I-560J3457D01*
G02Y1175002I0J3502D01*
G02X164518Y1174963I-3J-3502D01*
G01X164576Y1174955D01*
X164684Y1175003D01*
X164945Y1175408D01*
X164946Y1175526D01*
X164914Y1175575D01*
G02X164089Y1178386I4376J2811D01*
G02X165590Y1182042I5203J0D01*
G01X165619Y1182070D01*
X165648Y1182142D01*
Y1182504D01*
X165619Y1182576D01*
X165590Y1182604D01*
G02Y1189916I3702J3656D01*
G01X165619Y1189944D01*
X165648Y1190016D01*
Y1190378D01*
X165619Y1190450D01*
X165590Y1190478D01*
G02X164089Y1194134I3702J3656D01*
G02X168327Y1199246I5202J0D01*
G01X168372Y1199254D01*
X168444Y1199306D01*
G37*
G36*
G01X23039Y1240471D02*
G02X23500Y1240502I465J-3471D01*
G02Y1233498I0J-3502D01*
G02X20177Y1235893I0J3503D01*
G03X19961Y1236029I-190J-62D01*
G02X19500Y1235998I-465J3471D01*
G02Y1243002I0J3502D01*
G02X22823Y1240607I0J-3503D01*
G03X23039Y1240471I190J62D01*
G37*
G36*
G01X180649Y1237996D02*
X180699Y1238348D01*
X180681Y1238422D01*
X180658Y1238454D01*
G02X179998Y1240500I2841J2046D01*
G02X187002I3502J0D01*
G02X185661Y1237744I-3503J0D01*
G01X185630Y1237720D01*
X185592Y1237654D01*
X185542Y1237302D01*
X185560Y1237228D01*
X185583Y1237196D01*
G02X186243Y1235150I-2841J-2046D01*
G02X184743Y1232277I-3501J0D01*
G01X184703Y1232249D01*
X184658Y1232166D01*
X184649Y1231746D01*
X184690Y1231660D01*
X184729Y1231631D01*
G02X186102Y1228850I-2130J-2781D01*
G02X179098I-3502J0D01*
G02X180598Y1231723I3501J0D01*
G01X180638Y1231751D01*
X180683Y1231834D01*
X180692Y1232254D01*
X180651Y1232340D01*
X180612Y1232369D01*
G02X179239Y1235150I2130J2781D01*
G02X180580Y1237906I3503J0D01*
G01X180611Y1237930D01*
X180649Y1237996D01*
G37*
G36*
G01X73576Y115004D02*
G02X73241Y116500I3167J1495D01*
G02X76743Y112998I3502J0D01*
G02X75339Y113292I1J3502D01*
G03X74817Y112755I-160J-366D01*
G02X75152Y111259I-3167J-1495D01*
G02X71650Y114761I-3502J0D01*
G02X73054Y114467I-1J-3502D01*
G03X73576Y115004I160J366D01*
G37*
G36*
G01X165362Y216124D02*
G02X165062Y217543I3202J1418D01*
G02X172066I3502J0D01*
G02X171766Y216124I-3502J-1D01*
G03Y215962I182J-81D01*
G02X172066Y214543I-3202J-1418D01*
G02X168564Y211041I-3502J0D01*
G02X168117Y211070I3J3502D01*
G01X168057Y211077D01*
X167952Y211026D01*
X167700Y210611D01*
X167703Y210494D01*
X167738Y210444D01*
G02X168366Y208443I-2874J-2001D01*
G02X168066Y207024I-3502J-1D01*
G03Y206862I182J-81D01*
G02X168366Y205443I-3202J-1418D01*
G02X167200Y202834I-3502J0D01*
G01X167167Y202805D01*
X167133Y202726D01*
X167140Y202335D01*
X167176Y202258D01*
X167211Y202229D01*
G02X168466Y199543I-2247J-2686D01*
G02X168166Y198124I-3502J-1D01*
G03Y197962I182J-81D01*
G02X168466Y196543I-3202J-1418D01*
G02X166162Y193252I-3502J0D01*
G01X166101Y193230D01*
X166029Y193124D01*
X166042Y192615D01*
X166120Y192513D01*
X166182Y192494D01*
G02X168666Y189143I-1018J-3351D01*
G02X168366Y187724I-3502J-1D01*
G03Y187562I182J-81D01*
G02X168666Y186143I-3202J-1418D01*
G02X161662I-3502J0D01*
G02X161962Y187562I3502J1D01*
G03Y187724I-182J81D01*
G02X161662Y189143I3202J1418D01*
G02X163966Y192434I3502J0D01*
G01X164027Y192456D01*
X164099Y192562D01*
X164086Y193071D01*
X164008Y193173D01*
X163946Y193192D01*
G02X161462Y196543I1018J3351D01*
G02X161762Y197962I3502J1D01*
G03Y198124I-182J81D01*
G02X161462Y199543I3202J1418D01*
G02X162628Y202152I3502J0D01*
G01X162661Y202181D01*
X162695Y202260D01*
X162688Y202651D01*
X162652Y202728D01*
X162617Y202757D01*
G02X161362Y205443I2247J2686D01*
G02X161662Y206862I3502J1D01*
G03Y207024I-182J81D01*
G02X161362Y208443I3202J1418D01*
G02X164864Y211945I3502J0D01*
G02X165311Y211916I-3J-3502D01*
G01X165371Y211909D01*
X165476Y211960D01*
X165728Y212375D01*
X165725Y212492D01*
X165690Y212542D01*
G02X165062Y214543I2874J2001D01*
G02X165362Y215962I3502J1D01*
G03Y216124I-182J81D01*
G37*
G36*
G01X35386Y263409D02*
X35391Y263470D01*
G02X38389Y266636I3489J-301D01*
G03X38551Y266770I-28J198D01*
G02X41864Y269138I3313J-1134D01*
G02X45366Y265636I0J-3502D01*
G02X42355Y262169I-3502J0D01*
G03X42193Y262035I28J-198D01*
G02X38880Y259667I-3313J1134D01*
G02X36194Y260922I0J3502D01*
G01X36155Y260968D01*
X36039Y261002D01*
X35570Y260855D01*
X35494Y260760D01*
X35489Y260699D01*
G02X32000Y257498I-3489J301D01*
G02Y264502I0J3502D01*
G02X34686Y263247I0J-3502D01*
G01X34725Y263201D01*
X34841Y263167D01*
X35310Y263314D01*
X35386Y263409D01*
G37*
G36*
G01X24306Y272511D02*
X24253Y272507D01*
G02X24000Y272498I-251J3493D01*
G02X27502Y276000I0J3502D01*
G02X27258Y274715I-3502J-1D01*
G01X27238Y274666D01*
X27251Y274565D01*
X27514Y274208D01*
X27606Y274165D01*
X27659Y274169D01*
G02X27912Y274178I251J-3493D01*
G02X28825Y274057I0J-3502D01*
G01X28865Y274046D01*
X28944Y274057D01*
X29260Y274243D01*
X29308Y274306D01*
X29318Y274346D01*
G02X32716Y277002I3398J-846D01*
G02Y269998I0J-3502D01*
G02X31803Y270119I0J3502D01*
G01X31763Y270130D01*
X31684Y270119D01*
X31368Y269933D01*
X31320Y269870D01*
X31310Y269830D01*
G02X27912Y267174I-3398J846D01*
G02X25655Y267998I0J3503D01*
G01X25609Y268037D01*
X25491Y268051D01*
X25055Y267835D01*
X24995Y267733D01*
X24998Y267673D01*
G02X25002Y267500I-3498J-167D01*
G02X21500Y263998I-3502J0D01*
G02X19822Y264426I0J3503D01*
G03X19631I-96J-176D01*
G02X17953Y263998I-1678J3075D01*
G02Y271002I0J3502D01*
G02X19631Y270574I0J-3503D01*
G03X19822I95J176D01*
G02X21500Y271002I1678J-3075D01*
G02X23757Y270178I0J-3503D01*
G01X23803Y270139D01*
X23921Y270125D01*
X24357Y270341D01*
X24417Y270443D01*
X24414Y270503D01*
G02X24410Y270676I3498J167D01*
G02X24654Y271961I3502J1D01*
G01X24674Y272010D01*
X24661Y272111D01*
X24398Y272468D01*
X24306Y272511D01*
G37*
G36*
G01X166233Y284647D02*
X166207Y284699D01*
G02X165856Y286228I3151J1528D01*
G02X172860I3502J0D01*
G02X170126Y282811I-3502J0D01*
G01X170068Y282798D01*
X169986Y282716D01*
X169885Y282247D01*
X169925Y282137D01*
X169972Y282102D01*
X169975Y282100D01*
G03X170112Y282060I121J159D01*
G01X170229Y282070D01*
G03X170358Y282132I-16J199D01*
G02X172905Y283230I2547J-2405D01*
G02X175066Y282484I0J-3503D01*
G01X175101Y282456D01*
X175189Y282436D01*
X175580Y282525D01*
X175651Y282581D01*
X175671Y282622D01*
G02X178811Y284573I3140J-1551D01*
G02Y277569I0J-3502D01*
G02X176650Y278315I0J3503D01*
G01X176615Y278343D01*
X176527Y278363D01*
X176136Y278274D01*
X176065Y278218D01*
X176045Y278177D01*
G02X175979Y278050I-3140J1551D01*
G01X175955Y278006D01*
X175954Y277907D01*
X176151Y277524D01*
X176232Y277467D01*
X176281Y277461D01*
G02X179360Y273985I-423J-3476D01*
G02X179262Y273162I-3502J0D01*
G03X179280Y273020I194J-48D01*
G01X179336Y272916D01*
G03X179444Y272823I176J95D01*
G02X179677Y272730I-1181J-3297D01*
G03X179839I81J182D01*
G02X181258Y273030I1418J-3202D01*
G02X182677Y272730I1J-3502D01*
G03X182839I81J182D01*
G02X184258Y273030I1418J-3202D01*
G02X185677Y272730I1J-3502D01*
G03X185839I81J182D01*
G02X187258Y273030I1418J-3202D01*
G02Y266026I0J-3502D01*
G02X185839Y266326I-1J3502D01*
G03X185677I-81J-182D01*
G02X184258Y266026I-1418J3202D01*
G02X182839Y266326I-1J3502D01*
G03X182677I-81J-182D01*
G02X181258Y266026I-1418J3202D01*
G02X179839Y266326I-1J3502D01*
G03X179677I-81J-182D01*
G02X178258Y266026I-1418J3202D01*
G02X174756Y269528I0J3502D01*
G02X174854Y270351I3502J0D01*
G03X174836Y270493I-194J48D01*
G01X174780Y270597D01*
G03X174672Y270690I-176J-95D01*
G02X172356Y273985I1186J3295D01*
G02X172784Y275663I3503J0D01*
G01X172808Y275707D01*
X172809Y275806D01*
X172612Y276189D01*
X172531Y276246D01*
X172482Y276252D01*
G02X170788Y276938I422J3476D01*
G03X170651Y276978I-121J-159D01*
G01X170534Y276968D01*
G03X170405Y276906I16J-199D01*
G02X170074Y276598I-2546J2405D01*
G03X170001Y276446I127J-154D01*
G02X166499Y272981I-3502J37D01*
G02X164255Y273794I0J3503D01*
G01X164223Y273821D01*
X164142Y273845D01*
X163764Y273792D01*
X163693Y273748D01*
X163669Y273713D01*
G02X160777Y272186I-2892J1975D01*
G02X157275Y275688I0J3502D01*
G02X157322Y276261I3502J1D01*
G01X157330Y276305D01*
X157306Y276391D01*
X157046Y276691D01*
X156965Y276727D01*
X156921D01*
G02X156858Y276726I-87J3501D01*
G02X160360Y280228I0J3502D01*
G02X160313Y279655I-3502J-1D01*
G01X160305Y279611D01*
X160329Y279525D01*
X160589Y279225D01*
X160670Y279189D01*
X160714D01*
G02X160777Y279190I87J-3501D01*
G02X161177Y279167I-1J-3502D01*
G01X161228Y279161D01*
X161321Y279199D01*
X161600Y279536D01*
X161620Y279635D01*
X161604Y279684D01*
G02X161445Y280728I3343J1043D01*
G02X164947Y284230I3502J0D01*
G02X165755Y284135I-2J-3502D01*
G01X165812Y284122D01*
X165921Y284159D01*
X166220Y284532D01*
X166233Y284647D01*
G37*
G36*
G01X126113Y413124D02*
G02X125812Y414545I3201J1420D01*
G02X129314Y411043I3502J0D01*
G02X128085Y411266I1J3502D01*
G03X127579Y410729I-141J-374D01*
G02X127880Y409308I-3201J-1420D01*
G02X124378Y412810I-3502J0D01*
G02X125607Y412587I-1J-3502D01*
G03X126113Y413124I141J374D01*
G37*
G36*
G01X135227Y419265D02*
X135190Y419231D01*
G02X132850Y418335I-2339J2606D01*
G02Y425339I0J3502D01*
G02X136165Y422967I0J-3502D01*
G01X136181Y422919D01*
X136254Y422851D01*
X136675Y422741D01*
X136773Y422765D01*
X136810Y422799D01*
G02X139150Y423695I2339J-2606D01*
G02X142652Y420193I0J-3502D01*
G02X142617Y419698I-3502J-1D01*
G01X142608Y419638D01*
X142660Y419530D01*
X143081Y419278D01*
X143201Y419283D01*
X143250Y419320D01*
G02X145327Y420002I2076J-2820D01*
G02X141825Y416500I0J-3502D01*
G02X141860Y416995I3502J1D01*
G01X141869Y417055D01*
X141817Y417163D01*
X141396Y417415D01*
X141276Y417410D01*
X141227Y417373D01*
G02X139150Y416691I-2076J2820D01*
G02X135835Y419063I0J3502D01*
G01X135819Y419111D01*
X135746Y419179D01*
X135325Y419289D01*
X135227Y419265D01*
G37*
G36*
G01X65167Y466877D02*
X65108Y466879D01*
G02X61748Y470378I142J3499D01*
G02X68752I3502J0D01*
G02X67860Y468043I-3502J0D01*
G01X67821Y468000D01*
X67802Y467886D01*
X67989Y467445D01*
X68083Y467379D01*
X68142Y467377D01*
G02X71502Y463878I-142J-3499D01*
G02X71500Y463768I-3502J9D01*
G03X71548Y463632I200J-6D01*
G01X71624Y463542D01*
G03X71751Y463473I153J129D01*
G02X74802Y460000I-451J-3473D01*
G02X67798I-3502J0D01*
G02X67800Y460110I3502J-9D01*
G03X67752Y460246I-200J6D01*
G01X67676Y460336D01*
G03X67549Y460405I-153J-129D01*
G02X64498Y463878I451J3473D01*
G02X65390Y466213I3502J0D01*
G01X65429Y466256D01*
X65448Y466370D01*
X65261Y466811D01*
X65167Y466877D01*
G37*
G36*
G01X147903Y542151D02*
G02X146998Y544500I2596J2349D01*
G02X154002I3502J0D01*
G02X153167Y542230I-3503J0D01*
G03X153119Y542097I152J-130D01*
G01X153121Y541980D01*
G03X153172Y541849I200J2D01*
G02X154077Y539500I-2596J-2349D01*
G02X153207Y537190I-3502J0D01*
G03X153158Y537059I151J-131D01*
G01Y536941D01*
G03X153207Y536810I200J0D01*
G02Y532190I-2632J-2310D01*
G03X153158Y532059I151J-131D01*
G01Y531941D01*
G03X153207Y531810I200J0D01*
G02X154077Y529500I-2632J-2310D01*
G02X153924Y528475I-3502J-1D01*
G01X153911Y528433D01*
X153922Y528348D01*
X154131Y528016D01*
X154203Y527970D01*
X154247Y527963D01*
G02Y521037I-522J-3463D01*
G01X154203Y521030D01*
X154131Y520984D01*
X153922Y520652D01*
X153911Y520567D01*
X153924Y520525D01*
G02X154077Y519500I-3349J-1024D01*
G02X153924Y518475I-3502J-1D01*
G01X153911Y518433D01*
X153922Y518348D01*
X154131Y518016D01*
X154203Y517970D01*
X154247Y517963D01*
G02X157227Y514500I-522J-3463D01*
G02X154247Y511037I-3502J0D01*
G01X154203Y511030D01*
X154131Y510984D01*
X153922Y510652D01*
X153911Y510567D01*
X153924Y510525D01*
G02X154077Y509500I-3349J-1024D01*
G02X153207Y507190I-3502J0D01*
G03X153158Y507059I151J-131D01*
G01Y506941D01*
G03X153207Y506810I200J0D01*
G02Y502190I-2632J-2310D01*
G03X153158Y502059I151J-131D01*
G01Y501941D01*
G03X153207Y501810I200J0D01*
G02Y497190I-2632J-2310D01*
G03X153158Y497059I151J-131D01*
G01Y496941D01*
G03X153207Y496810I200J0D01*
G02X154077Y494500I-2632J-2310D01*
G02X153172Y492151I-3501J0D01*
G03X153121Y492020I149J-133D01*
G01X153119Y491903D01*
G03X153167Y491770I200J-3D01*
G02X154002Y489500I-2668J-2270D01*
G02X150853Y486016I-3502J0D01*
G01X150796Y486010D01*
X150707Y485942D01*
X150538Y485502D01*
X150559Y485392D01*
X150597Y485350D01*
G02X151502Y483000I-2597J-2349D01*
G02X144498I-3502J0D01*
G02X147647Y486484I3502J0D01*
G01X147704Y486490D01*
X147793Y486558D01*
X147962Y486998D01*
X147941Y487108D01*
X147903Y487150D01*
G02X146998Y489500I2597J2349D01*
G02X147903Y491849I3501J0D01*
G03X147954Y491980I-149J133D01*
G01X147956Y492097D01*
G03X147908Y492230I-200J3D01*
G02X147073Y494500I2668J2270D01*
G02X147142Y495190I3502J-2D01*
G01X147154Y495252D01*
X147104Y495366D01*
X146675Y495629D01*
X146551Y495621D01*
X146501Y495582D01*
G02X144324Y494823I-2177J2743D01*
G02X140822Y498325I0J3502D01*
G02X142483Y501304I3502J0D01*
G01X142521Y501328D01*
X142569Y501400D01*
X142627Y501792D01*
X142602Y501876D01*
X142572Y501909D01*
G02X141691Y504232I2622J2323D01*
G02X142206Y506061I3502J1D01*
G03X142233Y506199I-170J105D01*
G01X142200Y506390D01*
G02X142150Y506430I2162J2754D01*
G01X141934Y506368D01*
G03X141802Y506247I55J-192D01*
G02X138532Y503998I-3270J1253D01*
G02Y511002I0J3502D01*
G02X140524Y510380I0J-3501D01*
G01X140561Y510354D01*
X140649Y510340D01*
X141034Y510451D01*
X141101Y510509D01*
X141119Y510551D01*
G02X144335Y512668I3216J-1384D01*
G02X147023Y511411I0J-3503D01*
G01X147054Y511374D01*
X147139Y511337D01*
X147555Y511359D01*
X147636Y511405D01*
X147663Y511445D01*
G02X150053Y512963I2912J-1945D01*
G01X150097Y512970D01*
X150169Y513016D01*
X150378Y513348D01*
X150389Y513433D01*
X150376Y513475D01*
G02X150223Y514500I3349J1024D01*
G02X150376Y515525I3502J1D01*
G01X150389Y515567D01*
X150378Y515652D01*
X150169Y515984D01*
X150097Y516030D01*
X150053Y516037D01*
G02X147073Y519500I522J3463D01*
G02X147943Y521810I3502J0D01*
G03X147992Y521941I-151J131D01*
G01Y522059D01*
G03X147943Y522190I-200J0D01*
G02X147073Y524500I2632J2310D01*
G02X147943Y526810I3502J0D01*
G03X147992Y526941I-151J131D01*
G01Y527059D01*
G03X147943Y527190I-200J0D01*
G02Y531810I2632J2310D01*
G03X147992Y531941I-151J131D01*
G01Y532059D01*
G03X147943Y532190I-200J0D01*
G02Y536810I2632J2310D01*
G03X147992Y536941I-151J131D01*
G01Y537059D01*
G03X147943Y537190I-200J0D01*
G02X147073Y539500I2632J2310D01*
G02X147908Y541770I3503J0D01*
G03X147956Y541903I-152J130D01*
G01X147954Y542020D01*
G03X147903Y542151I-200J-2D01*
G37*
G36*
G01X103525Y563788D02*
X103957D01*
X104045Y563834D01*
X104073Y563876D01*
G02X106977Y565421I2904J-1957D01*
G02X110479Y561919I0J-3502D01*
G02X109887Y559971I-3501J0D01*
G01X109853Y559920D01*
Y559799D01*
X110127Y559390D01*
X110239Y559344D01*
X110299Y559356D01*
G02X111000Y559427I702J-3431D01*
G02X107498Y555925I0J-3502D01*
G02X108090Y557873I3501J0D01*
G01X108124Y557924D01*
Y558045D01*
X107850Y558454D01*
X107738Y558500D01*
X107678Y558488D01*
G02X106977Y558417I-702J3431D01*
G02X104073Y559962I0J3502D01*
G01X104045Y560004D01*
X103957Y560050D01*
X103525D01*
X103437Y560004D01*
X103409Y559962D01*
G02X100505Y558417I-2904J1957D01*
G02Y565421I0J3502D01*
G02X103409Y563876I0J-3502D01*
G01X103437Y563834D01*
X103525Y563788D01*
G37*
G36*
G01X24998Y573468D02*
Y620713D01*
G02X60436I17719J0D01*
G01Y573468D01*
G02X32664Y558876I-17719J0D01*
G01X32608Y558915D01*
X32473Y558908D01*
X32075Y558572D01*
X32046Y558440D01*
X32075Y558378D01*
G02X32402Y556900I-3175J-1478D01*
G02X28900Y560402I-3502J0D01*
G02X29784Y560289I2J-3502D01*
G01X29849Y560272D01*
X29974Y560324D01*
X30234Y560776D01*
X30216Y560910D01*
X30168Y560958D01*
G02X24998Y573468I12549J12509D01*
G37*
G36*
G01X19320Y669779D02*
X19286Y669808D01*
G02X18023Y672500I2237J2692D01*
G02X21525Y676002I3502J0D01*
G02X24883Y673495I0J-3502D01*
G03X25072Y673352I192J57D01*
G02X28525Y669850I-49J-3502D01*
G02X27262Y667158I-3500J0D01*
G01X27228Y667129D01*
X27190Y667049D01*
Y666651D01*
X27228Y666571D01*
X27262Y666542D01*
G02X28525Y663850I-2237J-2692D01*
G02X25291Y660358I-3502J0D01*
G03X25159Y660293I16J-199D01*
G01X25078Y660205D01*
G03X25026Y660067I148J-135D01*
G02X25027Y660000I-3501J-86D01*
G02X23764Y657308I-3500J0D01*
G01X23730Y657279D01*
X23692Y657199D01*
Y656801D01*
X23730Y656721D01*
X23764Y656692D01*
G02X25027Y654000I-2237J-2692D01*
G02X18023I-3502J0D01*
G02X19286Y656692I3500J0D01*
G01X19320Y656721D01*
X19358Y656801D01*
Y657199D01*
X19320Y657279D01*
X19286Y657308D01*
G02X18023Y660000I2237J2692D01*
G02X18027Y660166I3502J-1D01*
G01X18030Y660228D01*
X17966Y660332D01*
X17516Y660537D01*
X17395Y660517D01*
X17350Y660474D01*
G02X14925Y659498I-2425J2525D01*
G02X11423Y663000I0J3502D01*
G02X12686Y665692I3500J0D01*
G01X12720Y665721D01*
X12758Y665801D01*
Y666199D01*
X12720Y666279D01*
X12686Y666308D01*
G02X11423Y669000I2237J2692D01*
G02X14925Y672502I3502J0D01*
G02X18416Y669276I0J-3502D01*
G01X18421Y669217D01*
X18490Y669125D01*
X18938Y668956D01*
X19050Y668979D01*
X19093Y669019D01*
G02X19286Y669192I2432J-2519D01*
G01X19320Y669221D01*
X19358Y669301D01*
Y669699D01*
X19320Y669779D01*
G37*
G36*
G01X55988Y688656D02*
G02X55973Y688975I3487J324D01*
G02X62977I3502J0D01*
G02X62915Y688320I-3502J1D01*
G01X62904Y688260D01*
X62950Y688149D01*
X63360Y687878D01*
X63479D01*
X63530Y687912D01*
G02X65475Y688502I1945J-2911D01*
G02X68977Y685000I0J-3502D01*
G02X67714Y682308I-3502J1D01*
G01X67680Y682279D01*
X67642Y682199D01*
Y681801D01*
X67680Y681721D01*
X67714Y681692D01*
G02X68831Y680001I-2238J-2693D01*
G03X68967Y679866I192J57D01*
G02X71502Y676500I-967J-3366D01*
G02X70126Y673717I-3502J0D01*
G01X70082Y673684D01*
X70041Y673583D01*
X70109Y673128D01*
X70177Y673044D01*
X70228Y673025D01*
G02X72502Y669745I-1229J-3280D01*
G02X70844Y666768I-3502J0D01*
G01X70807Y666745D01*
X70760Y666675D01*
X70694Y666295D01*
X70714Y666213D01*
X70742Y666179D01*
G02X71502Y664000I-2742J-2178D01*
G02X68000Y660498I-3502J0D01*
G02X64644Y662999I0J3502D01*
G03X64508Y663134I-192J-57D01*
G02X61973Y666500I967J3366D01*
G02X62854Y668823I3503J0D01*
G03X62904Y668954I-150J132D01*
G01X62905Y669071D01*
G03X62856Y669204I-200J2D01*
G02X61998Y671500I2643J2296D01*
G02X64436Y674837I3503J0D01*
G01X64476Y674849D01*
X64536Y674901D01*
X64701Y675231D01*
X64706Y675310D01*
X64693Y675349D01*
G02X64644Y675499I3303J1162D01*
G03X64508Y675634I-192J-57D01*
G02X61973Y679000I967J3366D01*
G02X63236Y681692I3500J0D01*
G01X63270Y681721D01*
X63308Y681801D01*
Y682199D01*
X63270Y682279D01*
X63236Y682308D01*
G02X61973Y685000I2237J2692D01*
G02X62035Y685655I3502J-1D01*
G01X62046Y685715D01*
X62000Y685826D01*
X61590Y686097D01*
X61471D01*
X61420Y686063D01*
G02X60125Y685534I-1945J2912D01*
G03X59962Y685319I36J-197D01*
G02X59977Y685000I-3487J-324D01*
G02X58714Y682308I-3500J0D01*
G01X58680Y682279D01*
X58642Y682199D01*
Y681801D01*
X58680Y681721D01*
X58714Y681692D01*
G02X59977Y679000I-2237J-2692D01*
G02X58413Y676083I-3502J0D01*
G01X58371Y676055D01*
X58324Y675967D01*
Y675533D01*
X58371Y675445D01*
X58413Y675417D01*
G02X59977Y672500I-1938J-2917D01*
G02X58714Y669808I-3500J0D01*
G01X58680Y669779D01*
X58642Y669699D01*
Y669301D01*
X58680Y669221D01*
X58714Y669192D01*
G02X59977Y666500I-2237J-2692D01*
G02X58413Y663583I-3502J0D01*
G01X58371Y663555D01*
X58324Y663467D01*
Y663033D01*
X58371Y662945D01*
X58413Y662917D01*
G02X59977Y660000I-1938J-2917D01*
G02X58714Y657308I-3500J0D01*
G01X58680Y657279D01*
X58642Y657199D01*
Y656801D01*
X58680Y656721D01*
X58714Y656692D01*
G02X59842Y654962I-2239J-2693D01*
G01X59857Y654910D01*
X59934Y654836D01*
X60378Y654728D01*
X60481Y654759D01*
X60518Y654798D01*
G02X62779Y655890I2552J-2398D01*
G03X62959Y656052I-16J199D01*
G02X66400Y658902I3441J-652D01*
G02X69902Y655400I0J-3502D01*
G02X66691Y651910I-3502J0D01*
G03X66511Y651748I16J-199D01*
G02X65315Y649712I-3441J652D01*
G01X65266Y649671D01*
X65233Y649551D01*
X65403Y649077D01*
X65505Y649005D01*
X65569D01*
G02X69054Y645503I-17J-3502D01*
G02X62050I-3502J0D01*
G02X63307Y648191I3503J0D01*
G01X63356Y648232D01*
X63389Y648352D01*
X63219Y648826D01*
X63117Y648898D01*
X63053D01*
G02X59703Y651438I17J3502D01*
G01X59688Y651490D01*
X59611Y651564D01*
X59167Y651672D01*
X59064Y651641D01*
X59027Y651602D01*
G02X58023Y650859I-2552J2398D01*
G03X57912Y650679I89J-179D01*
G01Y650321D01*
G03X58023Y650141I200J-1D01*
G02X59977Y647000I-1548J-3141D01*
G02X58714Y644308I-3500J0D01*
G01X58680Y644279D01*
X58642Y644199D01*
Y643801D01*
X58680Y643721D01*
X58714Y643692D01*
G02X59977Y641000I-2237J-2692D01*
G02X52973I-3502J0D01*
G02X54236Y643692I3500J0D01*
G01X54270Y643721D01*
X54308Y643801D01*
Y644199D01*
X54270Y644279D01*
X54236Y644308D01*
G02X52973Y647000I2237J2692D01*
G02X54927Y650141I3502J0D01*
G03X55038Y650321I-89J179D01*
G01Y650679D01*
G03X54927Y650859I-200J1D01*
G02X52973Y654000I1548J3141D01*
G02X54236Y656692I3500J0D01*
G01X54270Y656721D01*
X54308Y656801D01*
Y657199D01*
X54270Y657279D01*
X54236Y657308D01*
G02X53117Y659005I2238J2693D01*
G03X52928Y659148I-192J-57D01*
G02X49475Y662650I49J3502D01*
G02X49518Y663197I3501J0D01*
G01X49527Y663256D01*
X49479Y663364D01*
X49069Y663626D01*
X48950Y663625D01*
X48900Y663591D01*
G02X46950Y662998I-1950J2910D01*
G02X43450Y666385I0J3502D01*
G03X43358Y666547I-200J-6D01*
G02Y672453I1881J2953D01*
G03X43450Y672615I-108J168D01*
G02X46950Y676002I3500J-115D01*
G02X50452Y672500I0J-3502D01*
G02X49189Y669808I-3500J0D01*
G01X49155Y669779D01*
X49117Y669699D01*
Y669301D01*
X49155Y669221D01*
X49189Y669192D01*
G02X50452Y666500I-2237J-2692D01*
G02X50409Y665953I-3501J0D01*
G01X50400Y665894D01*
X50448Y665786D01*
X50858Y665524D01*
X50977Y665525D01*
X51027Y665559D01*
G02X52709Y666142I1950J-2909D01*
G03X52841Y666207I-16J199D01*
G01X52922Y666295D01*
G03X52974Y666433I-148J135D01*
G02X52973Y666500I3501J86D01*
G02X54236Y669192I3500J0D01*
G01X54270Y669221D01*
X54308Y669301D01*
Y669699D01*
X54270Y669779D01*
X54236Y669808D01*
G02X52973Y672500I2237J2692D01*
G02X54537Y675417I3502J0D01*
G01X54579Y675445D01*
X54626Y675533D01*
Y675967D01*
X54579Y676055D01*
X54537Y676083D01*
G02X53117Y678005I1938J2917D01*
G03X52928Y678148I-192J-57D01*
G02X49475Y681650I49J3502D01*
G02X52799Y685147I3502J0D01*
G03X52988Y685328I-10J200D01*
G02X55825Y688441I3487J-328D01*
G03X55988Y688656I-36J197D01*
G37*
G36*
G01X122432Y705584D02*
G02X119500Y703998I-2932J1917D01*
G02Y711002I0J3502D01*
G02X122851Y708518I0J-3502D01*
G03X123568Y708416I382J117D01*
G02X126500Y710002I2932J-1917D01*
G02Y702998I0J-3502D01*
G02X123149Y705482I0J3502D01*
G03X122432Y705584I-382J-117D01*
G37*
G36*
G01X62706Y732484D02*
X62671Y732535D01*
G02X62068Y734500I2900J1965D01*
G02X65570Y738002I3502J0D01*
G02X68941Y735451I0J-3503D01*
G01X68953Y735408D01*
X69008Y735342D01*
X69363Y735177D01*
X69449Y735176D01*
X69489Y735194D01*
G02X70925Y735502I1436J-3194D01*
G02X72415Y735169I0J-3502D01*
G03X72585I85J181D01*
G02X74075Y735502I1490J-3169D01*
G02X77577Y732000I0J-3502D01*
G02X76559Y729532I-3501J0D01*
G01X76531Y729503D01*
X76501Y729431D01*
Y729069D01*
X76531Y728997D01*
X76559Y728968D01*
G02X77577Y726500I-2483J-2468D01*
G02X76707Y724190I-3502J0D01*
G03X76658Y724059I151J-131D01*
G01Y723941D01*
G03X76707Y723810I200J0D01*
G02X77577Y721500I-2632J-2310D01*
G02X76663Y719141I-3501J0D01*
G01X76625Y719099D01*
X76604Y718990D01*
X76766Y718551D01*
X76853Y718482D01*
X76909Y718475D01*
G02X79977Y715000I-434J-3475D01*
G02X78971Y712543I-3502J0D01*
G01X78942Y712514D01*
X78913Y712442D01*
X78915Y712080D01*
X78945Y712008D01*
X78973Y711979D01*
G02X80002Y709500I-2472J-2479D01*
G02X78984Y707032I-3501J0D01*
G01X78956Y707003D01*
X78926Y706931D01*
Y706569D01*
X78956Y706497D01*
X78984Y706468D01*
G02X80002Y704000I-2483J-2468D01*
G02X72998I-3502J0D01*
G02X74016Y706468I3501J0D01*
G01X74044Y706497D01*
X74074Y706569D01*
Y706931D01*
X74044Y707003D01*
X74016Y707032D01*
G02X72998Y709500I2483J2468D01*
G02X74004Y711957I3502J0D01*
G01X74033Y711986D01*
X74062Y712058D01*
X74060Y712420D01*
X74030Y712492D01*
X74002Y712521D01*
G02X72973Y715000I2472J2479D01*
G02X73887Y717359I3501J0D01*
G01X73925Y717401D01*
X73946Y717510D01*
X73784Y717949D01*
X73697Y718018D01*
X73641Y718025D01*
G02X71581Y719042I434J3475D01*
G01X71549Y719074D01*
X71466Y719105D01*
X71071Y719071D01*
X70994Y719027D01*
X70968Y718991D01*
G02X68100Y717498I-2868J2008D01*
G02Y724502I0J3502D01*
G02X70594Y723458I0J-3501D01*
G01X70626Y723426D01*
X70709Y723395D01*
X71104Y723429D01*
X71181Y723473D01*
X71207Y723509D01*
G02X71443Y723810I2870J-2007D01*
G03X71492Y723941I-151J131D01*
G01Y724059D01*
G03X71443Y724190I-200J0D01*
G02X70573Y726500I2632J2310D01*
G02X70889Y727953I3502J-1D01*
G01X70909Y727997D01*
X70904Y728093D01*
X70695Y728459D01*
X70614Y728512D01*
X70566Y728516D01*
G02X67554Y731049I359J3484D01*
G01X67542Y731092D01*
X67487Y731158D01*
X67132Y731323D01*
X67046Y731324D01*
X67006Y731306D01*
G02X65570Y730998I-1436J3194D01*
G02X64816Y731080I-1J3502D01*
G01X64756Y731093D01*
X64642Y731048D01*
X64364Y730639D01*
Y730516D01*
X64399Y730465D01*
G02X65002Y728500I-2900J-1965D01*
G02X61500Y732002I-3502J0D01*
G02X62254Y731920I1J-3502D01*
G01X62314Y731907D01*
X62428Y731952D01*
X62706Y732361D01*
Y732484D01*
G37*
G36*
G01X118186Y748230D02*
X118169Y748291D01*
G02X118034Y749253I3367J963D01*
G02X121536Y752755I3502J0D01*
G02X123322Y752265I-1J-3502D01*
G03X123528Y752267I101J172D01*
G02X125352Y752779I1823J-2990D01*
G02Y745775I0J-3502D01*
G02X123566Y746265I1J3502D01*
G03X123360Y746263I-101J-172D01*
G02X121536Y745751I-1823J2990D01*
G02X119509Y746398I1J3502D01*
G01X119457Y746434D01*
X119329Y746435D01*
X118917Y746143D01*
X118875Y746023D01*
X118892Y745962D01*
G02X119027Y745000I-3367J-963D01*
G02X118224Y742769I-3501J0D01*
G03X118188Y742580I154J-127D01*
G02X118359Y741500I-3331J-1081D01*
G02X118188Y740420I-3502J1D01*
G03X118224Y740231I190J-62D01*
G02X119027Y738000I-2698J-2231D01*
G02X119025Y737891I-3502J10D01*
G01X119024Y737853D01*
X119049Y737783D01*
X119277Y737520D01*
X119343Y737485D01*
X119382Y737481D01*
G02X122502Y734000I-382J-3481D01*
G02X119152Y730501I-3502J0D01*
G03X118964Y730339I8J-200D01*
G02X115525Y727498I-3439J661D01*
G02X112023Y731000I0J3502D01*
G02X113977Y734141I3502J0D01*
G03X114088Y734321I-89J179D01*
G01Y734679D01*
G03X113977Y734859I-200J1D01*
G02X112023Y738000I1548J3141D01*
G02X112194Y739080I3502J-1D01*
G03X112158Y739269I-190J62D01*
G02Y743731I2698J2231D01*
G03X112194Y743920I-154J127D01*
G02X112023Y745000I3331J1081D01*
G02X115525Y748502I3502J0D01*
G02X117552Y747855I-1J-3502D01*
G01X117604Y747819D01*
X117732Y747818D01*
X118144Y748110D01*
X118186Y748230D01*
G37*
G36*
G01X165415Y753331D02*
G02X163925Y752998I-1490J3169D01*
G02Y760002I0J3502D01*
G02X165415Y759669I0J-3502D01*
G03X165585I85J181D01*
G02X167075Y760002I1490J-3169D01*
G02X170577Y756500I0J-3502D01*
G02X170376Y755331I-3502J0D01*
G01X170357Y755276D01*
X170381Y755165D01*
X170715Y754826D01*
X170826Y754800D01*
X170881Y754818D01*
G02X172000Y755002I1120J-3318D01*
G02X175502Y751500I0J-3502D01*
G02X173070Y748166I-3501J0D01*
G03X172957Y748073I62J-190D01*
G01X172899Y747969D01*
G03X172879Y747824I174J-98D01*
G02X172977Y747000I-3404J-823D01*
G02X172972Y746814I-3502J1D01*
G03X173081Y746625I200J-11D01*
G02Y740375I-1581J-3125D01*
G03X172972Y740186I91J-178D01*
G02X172977Y740000I-3497J-187D01*
G02X172867Y739128I-3502J-1D01*
G03X172981Y738895I194J-50D01*
G02X175088Y735683I-1395J-3212D01*
G02X173030Y732492I-3503J0D01*
G03X172916Y732347I82J-182D01*
G02X169475Y729498I-3441J654D01*
G02X165973Y733000I0J3502D01*
G02X168031Y736191I3503J0D01*
G03X168145Y736336I-82J182D01*
G02X168194Y736555I3440J-655D01*
G03X168080Y736788I-194J50D01*
G02X165973Y740000I1395J3212D01*
G02X167894Y743125I3502J0D01*
G03X168003Y743314I-91J178D01*
G02X167998Y743500I3497J187D01*
G02X168003Y743686I3502J-1D01*
G03X167894Y743875I-200J11D01*
G02X165973Y747000I1581J3125D01*
G02X168405Y750334I3501J0D01*
G03X168518Y750427I-62J190D01*
G01X168576Y750531D01*
G03X168596Y750676I-174J98D01*
G02X168498Y751500I3404J823D01*
G02X168699Y752669I3502J0D01*
G01X168718Y752724D01*
X168694Y752835D01*
X168360Y753174D01*
X168249Y753200D01*
X168194Y753182D01*
G02X167075Y752998I-1120J3318D01*
G02X165585Y753331I0J3502D01*
G03X165415I-85J-181D01*
G37*
G36*
G01X62014Y774749D02*
X61994Y774688D01*
G02X58673Y772298I-3321J1112D01*
G02Y779302I0J3502D01*
G02X61928Y777091I0J-3501D01*
G01X61952Y777032D01*
X62056Y776964D01*
X62559Y776977D01*
X62659Y777051D01*
X62679Y777112D01*
G02X66000Y779502I3321J-1112D01*
G02X69502Y776000I0J-3502D01*
G02X69447Y775381I-3502J-1D01*
G01X69440Y775342D01*
X69455Y775268D01*
X69653Y774971D01*
X69716Y774928D01*
X69754Y774920D01*
G02X72502Y771500I-754J-3420D01*
G02X70624Y768397I-3503J0D01*
G01X70576Y768372D01*
X70519Y768283D01*
X70499Y767830D01*
X70547Y767736D01*
X70592Y767707D01*
G02X72196Y764764I-1898J-2943D01*
G02X65192I-3502J0D01*
G02X67070Y767867I3503J0D01*
G01X67118Y767892D01*
X67175Y767981D01*
X67195Y768434D01*
X67147Y768528D01*
X67102Y768557D01*
G02X65498Y771500I1898J2943D01*
G02X65553Y772119I3502J1D01*
G01X65560Y772158D01*
X65545Y772232D01*
X65347Y772529D01*
X65284Y772572D01*
X65246Y772580D01*
G02X62745Y774709I754J3420D01*
G01X62721Y774768D01*
X62617Y774836D01*
X62114Y774823D01*
X62014Y774749D01*
G37*
G36*
G01X72605Y850530D02*
G02X71998Y852500I2895J1970D01*
G02X75500Y848998I3502J0D01*
G02X74725Y849085I1J3502D01*
G03X74305Y848470I-89J-390D01*
G02X74912Y846500I-2895J-1970D01*
G02X71410Y850002I-3502J0D01*
G02X72185Y849915I-1J-3502D01*
G03X72605Y850530I89J390D01*
G37*
G36*
G01X29423Y926822D02*
G02X29123Y928241I3202J1418D01*
G02X36127I3502J0D01*
G02X35827Y926822I-3502J-1D01*
G03Y926660I182J-81D01*
G02X36127Y925241I-3202J-1418D01*
G02X33823Y921950I-3502J0D01*
G01X33762Y921928D01*
X33690Y921822D01*
X33703Y921313D01*
X33781Y921211D01*
X33843Y921192D01*
G02X36327Y917841I-1018J-3351D01*
G02X36027Y916422I-3502J-1D01*
G03Y916260I182J-81D01*
G02X36327Y914841I-3202J-1418D01*
G02X29323I-3502J0D01*
G02X29623Y916260I3502J1D01*
G03Y916422I-182J81D01*
G02X29323Y917841I3202J1418D01*
G02X31627Y921132I3502J0D01*
G01X31688Y921154D01*
X31760Y921260D01*
X31747Y921769D01*
X31669Y921871D01*
X31607Y921890D01*
G02X29123Y925241I1018J3351D01*
G02X29423Y926660I3502J1D01*
G03Y926822I-182J81D01*
G37*
G36*
G01X23383Y999097D02*
G02X26500Y1001002I3117J-1598D01*
G02X26905Y1000978I-4J-3502D01*
G03X27123Y1001129I23J199D01*
G02X30522Y1003790I3399J-840D01*
G02X34024Y1000288I0J-3502D01*
G02X32190Y997209I-3502J0D01*
G01X32133Y997178D01*
X32077Y997063D01*
X32165Y996561D01*
X32256Y996472D01*
X32320Y996462D01*
G02X35293Y993000I-529J-3462D01*
G02X28289I-3502J0D01*
G02X28382Y993803I3502J1D01*
G01X28395Y993859D01*
X28361Y993964D01*
X28002Y994269D01*
X27893Y994286D01*
X27840Y994265D01*
G02X27248Y994079I-1342J3235D01*
G01X27205Y994069D01*
X27135Y994017D01*
X26950Y993670D01*
X26945Y993583D01*
X26961Y993542D01*
G02X27204Y992261I-3259J-1282D01*
G02X23702Y988759I-3502J0D01*
G01X23677D01*
G03X23477Y988583I-1J-200D01*
G02X20000Y985498I-3477J417D01*
G02Y992502I0J3502D01*
G01X20025D01*
G03X20225Y992678I1J200D01*
G02X20310Y993131I3477J-418D01*
G03X20272Y993306I-194J50D01*
G02X19507Y995491I2738J2185D01*
G02X23009Y998993I3502J0D01*
G02X23195Y998988I-1J-3502D01*
G03X23383Y999097I10J200D01*
G37*
G36*
G01X143801Y1005318D02*
G02X143142Y1007363I2844J2045D01*
G02X146223Y1010840I3502J0D01*
G03X146392Y1010985I-24J199D01*
G02X149769Y1013561I3377J-926D01*
G02X153271Y1010059I0J-3502D01*
G02X150523Y1006639I-3502J0D01*
G01X150476Y1006629D01*
X150403Y1006569D01*
X150233Y1006185D01*
X150238Y1006091D01*
X150263Y1006049D01*
G02X150731Y1004299I-3034J-1749D01*
G02X148743Y1001141I-3502J0D01*
G01X148700Y1001121D01*
X148643Y1001047D01*
X148560Y1000642D01*
X148584Y1000552D01*
X148615Y1000517D01*
G02X149467Y998551I-2633J-2309D01*
G03X149543Y998413I199J20D01*
G02X150895Y995649I-2149J-2764D01*
G02X147393Y992147I-3502J0D01*
G02X146016Y992429I0J3503D01*
G03X145859I-79J-184D01*
G02X144482Y992147I-1377J3221D01*
G02X141650Y993589I0J3502D01*
G03X141527Y993667I-161J-118D01*
G01X141411Y993690D01*
G03X141267Y993665I-40J-196D01*
G02X140839Y993441I-1834J2983D01*
G03X140720Y993258I81J-183D01*
G01Y992891D01*
G03X140839Y992708I200J0D01*
G02X142937Y989500I-1404J-3208D01*
G02X135933I-3502J0D01*
G02X138031Y992708I3502J0D01*
G03X138150Y992891I-81J183D01*
G01Y993258D01*
G03X138031Y993441I-200J0D01*
G02X137274Y993893I1403J3209D01*
G01X137239Y993921D01*
X137151Y993941D01*
X136760Y993852D01*
X136689Y993796D01*
X136669Y993755D01*
G02X133529Y991804I-3140J1551D01*
G02Y998808I0J3502D01*
G02X135690Y998062I0J-3503D01*
G01X135725Y998034D01*
X135813Y998014D01*
X136204Y998103D01*
X136275Y998159D01*
X136295Y998200D01*
G02X136361Y998327I3140J-1551D01*
G01X136385Y998371D01*
X136386Y998470D01*
X136189Y998853D01*
X136108Y998910D01*
X136059Y998916D01*
G02X132980Y1002392I423J3476D01*
G02X139984I3502J0D01*
G02X139556Y1000714I-3503J0D01*
G01X139532Y1000670D01*
X139531Y1000571D01*
X139728Y1000188D01*
X139809Y1000131D01*
X139858Y1000125D01*
G02X141962Y999073I-423J-3476D01*
G01X141999Y999035D01*
X142101Y999005D01*
X142541Y999109D01*
X142618Y999182D01*
X142633Y999233D01*
G02X144468Y1001366I3349J-1025D01*
G01X144511Y1001386D01*
X144568Y1001460D01*
X144651Y1001865D01*
X144627Y1001955D01*
X144596Y1001990D01*
G02X143727Y1004299I2633J2309D01*
G02X143833Y1005153I3502J-1D01*
G03X143801Y1005318I-194J48D01*
G37*
G36*
G01X69469Y1011080D02*
G02X68498Y1013500I2530J2420D01*
G02X75502I3502J0D01*
G02X75477Y1013082I-3502J0D01*
G03X75531Y1012920I199J-24D01*
G02X76502Y1010500I-2530J-2420D01*
G02X73607Y1007051I-3502J0D01*
G01X73570Y1007044D01*
X73505Y1007004D01*
X73295Y1006722D01*
X73275Y1006648D01*
X73280Y1006610D01*
G02X73304Y1006198I-3478J-409D01*
G02X69802Y1002696I-3502J0D01*
G02X67120Y1003946I0J3502D01*
G01X67093Y1003978D01*
X67019Y1004015D01*
X66644Y1004035D01*
X66567Y1004006D01*
X66537Y1003977D01*
G02X64108Y1002998I-2429J2524D01*
G02X61194Y1004558I0J3502D01*
G03X61079Y1004640I-166J-111D01*
G01X60966Y1004670D01*
G03X60825Y1004656I-52J-193D01*
G02X59907Y1004350I-1556J3137D01*
G03X59744Y1004145I37J-197D01*
G02X59747Y1004000I-3499J-145D01*
G02X52743I-3502J0D01*
G02X53116Y1005572I3502J-1D01*
G03X53110Y1005761I-179J89D01*
G02X52648Y1007500I3040J1739D01*
G02X52738Y1008289I3502J0D01*
G01X52749Y1008337D01*
X52725Y1008431D01*
X52438Y1008748D01*
X52346Y1008782D01*
X52297Y1008775D01*
G02X52070Y1008754I-436J3475D01*
G01X52021Y1008751D01*
X51938Y1008702D01*
X51714Y1008342D01*
X51707Y1008246D01*
X51725Y1008201D01*
G02X51994Y1006856I-3233J-1346D01*
G02X44990I-3502J0D01*
G02X45733Y1009013I3502J0D01*
G03X45774Y1009154I-158J122D01*
G01X45763Y1009273D01*
G03X45696Y1009405I-199J-18D01*
G02X45182Y1009965I2308J2634D01*
G01X45145Y1010016D01*
X45027Y1010056D01*
X44546Y1009921D01*
X44467Y1009825D01*
X44461Y1009762D01*
G02X42476Y1006897I-3489J297D01*
G01X42441Y1006880D01*
X42389Y1006824D01*
X42263Y1006490D01*
X42265Y1006414D01*
X42280Y1006378D01*
G02X42563Y1005000I-3219J-1379D01*
G02X35559I-3502J0D01*
G02X37557Y1008162I3501J0D01*
G01X37592Y1008179D01*
X37644Y1008235D01*
X37770Y1008569D01*
X37768Y1008645D01*
X37753Y1008681D01*
G02X37470Y1010059I3219J1379D01*
G02X40972Y1013561I3502J0D01*
G02X43795Y1012132I0J-3503D01*
G01X43832Y1012081D01*
X43950Y1012041D01*
X44431Y1012176D01*
X44510Y1012272D01*
X44516Y1012335D01*
G02X48005Y1015540I3489J-297D01*
G02X49661Y1015124I0J-3502D01*
G03X49869Y1015135I95J176D01*
G02X51852Y1015751I1984J-2886D01*
G02X55354Y1012249I0J-3502D01*
G02X55264Y1011460I-3502J0D01*
G01X55253Y1011412D01*
X55277Y1011318D01*
X55564Y1011001D01*
X55656Y1010967D01*
X55705Y1010974D01*
G02X56150Y1011002I442J-3474D01*
G02X57328Y1010798I0J-3503D01*
G03X57496Y1010814I67J188D01*
G02X59268Y1011295I1771J-3021D01*
G02X62182Y1009735I0J-3502D01*
G03X62297Y1009653I166J111D01*
G01X62410Y1009623D01*
G03X62551Y1009637I52J193D01*
G02X64108Y1010002I1557J-3138D01*
G02X66790Y1008752I0J-3502D01*
G01X66817Y1008720D01*
X66891Y1008683D01*
X67266Y1008663D01*
X67343Y1008692D01*
X67373Y1008721D01*
G02X69195Y1009647I2429J-2523D01*
G01X69232Y1009654D01*
X69297Y1009694D01*
X69507Y1009976D01*
X69527Y1010050D01*
X69522Y1010088D01*
G02X69498Y1010500I3478J409D01*
G02X69523Y1010918I3502J0D01*
G03X69469Y1011080I-199J24D01*
G37*
G36*
G01X114907Y1149932D02*
X114878Y1149989D01*
G02X114498Y1151575I3122J1587D01*
G02X121502I3502J0D01*
G02X121501Y1151495I-3502J4D01*
G01X121500Y1151434D01*
X121563Y1151334D01*
X122005Y1151129D01*
X122122Y1151147D01*
X122167Y1151187D01*
G02X124500Y1152077I2333J-2613D01*
G02X128002Y1148575I0J-3502D01*
G02X127610Y1146965I-3502J0D01*
G01X127588Y1146923D01*
X127586Y1146833D01*
X127752Y1146463D01*
X127821Y1146405D01*
X127866Y1146393D01*
G02X130502Y1143000I-866J-3393D01*
G02X127053Y1139498I-3502J0D01*
G01X127003D01*
X126915Y1139449D01*
X126681Y1139081D01*
X126674Y1138981D01*
X126695Y1138935D01*
G02X127002Y1137500I-3195J-1434D01*
G02X124206Y1134070I-3502J0D01*
G01X124157Y1134060D01*
X124082Y1133998D01*
X123914Y1133602D01*
X123923Y1133505D01*
X123950Y1133463D01*
G02X124401Y1132411I-2950J-1887D01*
G01X124412Y1132367D01*
X124469Y1132297D01*
X124833Y1132127D01*
X124923D01*
X124964Y1132147D01*
G02X126500Y1132502I1536J-3147D01*
G02Y1125498I0J-3502D01*
G02X124289Y1126284I0J3503D01*
G01X124258Y1126310D01*
X124182Y1126332D01*
X123820Y1126295D01*
X123750Y1126257D01*
X123725Y1126225D01*
G02X121000Y1124923I-2725J2201D01*
G02X117498Y1128425I0J3502D01*
G02X117831Y1129915I3502J0D01*
G03Y1130085I-181J85D01*
G02X117498Y1131575I3169J1490D01*
G02X120294Y1135005I3502J0D01*
G01X120343Y1135015D01*
X120418Y1135077D01*
X120586Y1135473D01*
X120577Y1135570D01*
X120550Y1135612D01*
G02X119998Y1137500I2950J1887D01*
G02X123447Y1141002I3502J0D01*
G01X123497D01*
X123585Y1141051D01*
X123819Y1141419D01*
X123826Y1141519D01*
X123805Y1141565D01*
G02X123498Y1143000I3195J1434D01*
G02X123890Y1144610I3502J0D01*
G01X123912Y1144652D01*
X123914Y1144742D01*
X123748Y1145112D01*
X123679Y1145170D01*
X123634Y1145182D01*
G02X120998Y1148575I866J3393D01*
G02X120999Y1148655I3502J-4D01*
G01X121000Y1148716D01*
X120937Y1148816D01*
X120495Y1149021D01*
X120378Y1149003D01*
X120333Y1148963D01*
G02X118000Y1148073I-2333J2613D01*
G02X116582Y1148373I0J3501D01*
G01X116523Y1148399D01*
X116400Y1148374D01*
X116052Y1148008D01*
X116034Y1147883D01*
X116063Y1147826D01*
G02X116443Y1146240I-3122J-1587D01*
G02X112941Y1149742I-3502J0D01*
G02X114359Y1149442I0J-3501D01*
G01X114418Y1149416D01*
X114541Y1149441D01*
X114889Y1149807D01*
X114907Y1149932D01*
G37*
G36*
G01X71459Y1197233D02*
G02X70003Y1200075I2046J2842D01*
G02X77007I3502J0D01*
G02X76965Y1199535I-3502J1D01*
G03X77046Y1199342I198J-31D01*
G02X78497Y1196690I-2046J-2842D01*
G01X78500Y1196636D01*
X78557Y1196547D01*
X78961Y1196340D01*
X79066Y1196345D01*
X79112Y1196374D01*
G02X81000Y1196927I1889J-2949D01*
G02Y1189923I0J-3502D01*
G02X80082Y1190046I2J3502D01*
G01X80026Y1190061D01*
X79916Y1190027D01*
X79604Y1189667D01*
X79587Y1189553D01*
X79610Y1189500D01*
G02X79902Y1188100I-3210J-1400D01*
G02X76400Y1191602I-3502J0D01*
G02X77318Y1191479I-2J-3502D01*
G01X77374Y1191464D01*
X77484Y1191498D01*
X77796Y1191858D01*
X77813Y1191972D01*
X77790Y1192025D01*
G02X77503Y1193235I3210J1400D01*
G01X77500Y1193289D01*
X77443Y1193378D01*
X77039Y1193585D01*
X76934Y1193580D01*
X76888Y1193551D01*
G02X75000Y1192998I-1889J2949D01*
G02X71498Y1196500I0J3502D01*
G02X71540Y1197040I3502J-1D01*
G03X71459Y1197233I-198J31D01*
G37*
G54D16*
X159051Y671661D03*
X47813Y833013D03*
X45240Y657000D03*
X79500Y449925D03*
X156962Y692037D03*
X61000Y1172500D03*
X187050Y652000D03*
X74979Y437559D03*
X79463Y429962D03*
X73500Y562200D03*
X136500Y728500D03*
X187925Y701000D03*
X32760Y669500D03*
X120000Y504500D03*
X127000Y1166000D03*
X78000Y782500D03*
X118079Y639954D03*
X45240Y682000D03*
X125200Y453800D03*
X107000Y400425D03*
X112441Y418434D03*
X141327Y822814D03*
X91059Y452760D03*
X85500Y472975D03*
X60475Y1152000D03*
X77816Y764764D03*
X73747Y570715D03*
X114000Y591000D03*
X97000Y569153D03*
X110000Y1128425D03*
X69018Y783764D03*
X142500Y1183500D03*
X142088Y1131281D03*
X142500Y1176000D03*
X68543Y1128650D03*
X125000Y1198000D03*
X69018Y1147650D03*
X68700Y400000D03*
X144827Y763510D03*
X128000Y512500D03*
X61000Y810000D03*
X120000Y512500D03*
X64231Y1115268D03*
X57500Y1181000D03*
X33500Y694425D03*
X26500Y732500D03*
X132175Y1117325D03*
X100835Y446500D03*
X64500Y287000D03*
X72500Y283771D03*
X47561Y280228D03*
X156858Y1007000D03*
X44500Y272767D03*
X134575Y659000D03*
X95000Y462740D03*
X12500Y679000D03*
X141900Y645410D03*
X118711Y797500D03*
X120500Y845000D03*
X101500Y824271D03*
X14925Y690000D03*
X104500Y834500D03*
X150300Y645900D03*
X128500Y554925D03*
X74000Y1026000D03*
X119500Y992000D03*
X167642Y682217D03*
X136500Y742000D03*
X128065Y725566D03*
X127983Y736234D03*
X146000Y729000D03*
X167060Y692500D03*
X139150Y712500D03*
X177000Y522000D03*
X135245Y407228D03*
X61576Y762200D03*
X128000Y251000D03*
X109500Y1139500D03*
X107966Y408260D03*
X115788Y573787D03*
X64843Y1194000D03*
X64850Y1179000D03*
X58612Y740500D03*
X60000Y696984D03*
X98780Y617000D03*
X134800Y826614D03*
X78500Y504500D03*
X183500Y299500D03*
X129112Y978769D03*
X182058Y1022519D03*
X120000Y581500D03*
X167679Y674254D03*
X166547Y663500D03*
X124499Y660000D03*
X123401Y669102D03*
X13500Y862500D03*
X170000Y504500D03*
X71689Y302000D03*
X86500Y512500D03*
X177000Y514000D03*
X86500Y504500D03*
X37500Y520500D03*
X95184Y493787D03*
X169000Y514000D03*
Y522000D03*
X49250Y516750D03*
X37500Y512500D03*
X29500D03*
Y520500D03*
X21000Y644000D03*
X52800Y813500D03*
X83300Y624100D03*
X74500Y475000D03*
X141500Y516500D03*
X49689Y474203D03*
X151300Y756400D03*
X113500Y476000D03*
X102500Y979500D03*
X56000Y1203273D03*
X141327Y398000D03*
X165500Y1229900D03*
X84000Y844950D03*
X87500Y522800D03*
X20452Y513547D03*
X126070Y493931D03*
X117500Y857575D03*
X192000Y1240500D03*
X82500Y389500D03*
X135750Y132750D03*
X62716Y129542D03*
X69350Y711940D03*
X118490Y495330D03*
X23000Y760000D03*
X122500Y102000D03*
X122000Y463000D03*
X123500Y59500D03*
X77400Y775000D03*
X58700Y110900D03*
X61300Y66900D03*
X84400Y64200D03*
X71650Y94259D03*
X79500Y86925D03*
Y104425D03*
X88900Y119300D03*
X112000Y88700D03*
X114500Y127000D03*
X118475Y83500D03*
X135500Y70441D03*
X127000Y77500D03*
X135000Y120500D03*
X127500Y129500D03*
X87500Y83300D03*
G54D17*
X101772Y1287047D03*
G54D15*
X44000Y17500D03*
X178500D03*
X20000Y1307000D03*
G54D14*
X101771Y928778D03*
X160827Y597090D03*
%LPD*%
G75*
G54D10*
X-32318Y1152816D03*
X-22318D03*
G54D11*
X3005Y30675D03*
Y50675D03*
Y70675D03*
Y90675D03*
Y110675D03*
Y130675D03*
Y150675D03*
Y170675D03*
Y190675D03*
Y210675D03*
Y230675D03*
Y250675D03*
Y270675D03*
Y290675D03*
Y310675D03*
Y330675D03*
Y350675D03*
Y370675D03*
Y390675D03*
Y410675D03*
Y430675D03*
Y450675D03*
Y470675D03*
Y490675D03*
Y510675D03*
Y530675D03*
Y550675D03*
Y570675D03*
Y590675D03*
Y610675D03*
Y630675D03*
Y650675D03*
Y670675D03*
Y690675D03*
Y710675D03*
Y730675D03*
Y750675D03*
Y770675D03*
Y790675D03*
Y810675D03*
Y830675D03*
Y850675D03*
Y870675D03*
Y890675D03*
Y910675D03*
Y930675D03*
Y950675D03*
Y970675D03*
Y990675D03*
Y1010675D03*
Y1030675D03*
Y1050675D03*
Y1070675D03*
Y1090675D03*
Y1110675D03*
Y1130675D03*
Y1150675D03*
Y1170675D03*
Y1190675D03*
Y1210675D03*
Y1230675D03*
Y1250675D03*
Y1270675D03*
Y1290675D03*
Y1310675D03*
X15868Y3010D03*
X29291Y235093D03*
X26791D03*
X31871D03*
X26791Y232593D03*
X29331D03*
X31871D03*
X18185Y312228D03*
X21185D03*
Y315228D03*
X18185D03*
X24185Y312228D03*
X27185D03*
Y315228D03*
X24185D03*
X31871Y961865D03*
X26791D03*
X29291D03*
X31871Y959365D03*
X29331D03*
X26791D03*
X24685Y1041800D03*
X18185Y1041900D03*
X21385D03*
X24685Y1038800D03*
X21385Y1038900D03*
X18185D03*
X13492Y1049256D03*
Y1051756D03*
Y1046676D03*
X16017Y1323770D03*
X34927Y3006D03*
X54927D03*
X50967Y246228D03*
X53967D03*
X48477Y233457D03*
X51477D03*
X54477D03*
X39167Y230228D03*
X42167D03*
X51456Y230214D03*
X48456D03*
X54456D03*
X50021Y313863D03*
X52561D03*
Y311363D03*
X50061D03*
X47481D03*
Y313863D03*
X37185Y316228D03*
X40185D03*
X48631Y964607D03*
Y962107D03*
X48731Y959507D03*
Y957007D03*
X42167Y958400D03*
X39167D03*
X48731Y972307D03*
Y974807D03*
X48631Y969707D03*
Y967207D03*
X40585Y1041300D03*
X37585D03*
X50561Y1038135D03*
X53061D03*
Y1040635D03*
X50521D03*
X47981D03*
Y1038135D03*
X35517Y1323770D03*
X56017D03*
X61802Y25927D03*
X68508Y50969D03*
X56967Y246228D03*
X76017Y1323770D03*
X96017D03*
X111522Y39800D03*
X114522D03*
X111522Y44800D03*
X114522D03*
X111522Y47300D03*
Y49800D03*
X114522D03*
Y52300D03*
X111522D03*
X114522Y47300D03*
X111522Y42300D03*
X114522D03*
X127482Y312228D03*
X127182Y1039000D03*
X116017Y1323770D03*
X146740Y3016D03*
X141748Y26922D03*
X135014Y50977D03*
X133482Y315228D03*
Y312228D03*
X130482Y315228D03*
Y312228D03*
X146482Y316228D03*
X127482Y315228D03*
X127182Y1055000D03*
Y1042000D03*
X133382Y1055000D03*
Y1042000D03*
Y1039000D03*
X130382Y1055000D03*
Y1042000D03*
Y1039000D03*
X146482Y1043000D03*
X136017Y1323770D03*
X165799Y3002D03*
X153022Y232593D03*
X150482D03*
X155562D03*
X165562Y230593D03*
X163022D03*
X150482Y235093D03*
X152982D03*
X155562D03*
X156778Y311363D03*
Y313863D03*
X159318D03*
X161858D03*
Y311363D03*
X159358D03*
X149482Y316228D03*
X153622Y962514D03*
X151082D03*
Y965014D03*
X153582D03*
X156162D03*
Y962514D03*
X167858Y961800D03*
X164858D03*
X149482Y1043000D03*
X156778Y1038135D03*
Y1040635D03*
X159318D03*
X161858D03*
Y1038135D03*
X159358D03*
X156017Y1323770D03*
X185799Y3002D03*
X179358Y230328D03*
Y227328D03*
X182358Y230328D03*
X185358D03*
X182358Y227328D03*
X185358D03*
X185658Y243528D03*
X182658D03*
X179658D03*
X180658Y956100D03*
X186658D03*
Y952900D03*
X180658D03*
X183758Y956200D03*
Y953000D03*
X180658Y969000D03*
X186658D03*
X183758Y969100D03*
X176017Y1323770D03*
X194471Y1321882D03*
X199120Y9903D03*
X200536Y29059D03*
Y49059D03*
Y69059D03*
Y109059D03*
Y89059D03*
Y129059D03*
Y149059D03*
Y169059D03*
Y189059D03*
Y209059D03*
Y249059D03*
Y229059D03*
Y269059D03*
Y289059D03*
Y309059D03*
Y329059D03*
Y349059D03*
Y369059D03*
Y409059D03*
Y389059D03*
Y429059D03*
Y449059D03*
Y469059D03*
Y489059D03*
Y509059D03*
Y549059D03*
Y529059D03*
Y569059D03*
Y589059D03*
Y609059D03*
Y629059D03*
Y649059D03*
Y669059D03*
Y709059D03*
Y689059D03*
Y729059D03*
Y749059D03*
Y769059D03*
Y789059D03*
Y809059D03*
Y849059D03*
Y829059D03*
Y869059D03*
Y889059D03*
Y909059D03*
Y929059D03*
Y947059D03*
Y969059D03*
Y1009059D03*
Y989059D03*
Y1029059D03*
Y1049059D03*
Y1069059D03*
Y1089059D03*
Y1109059D03*
Y1149059D03*
Y1129059D03*
Y1169059D03*
Y1189059D03*
Y1209059D03*
Y1229059D03*
Y1249059D03*
Y1289059D03*
Y1269059D03*
Y1309059D03*
G54D12*
G01X-320500Y-470483D02*
Y2626000D01*
X2967000D01*
Y-470483D01*
X-320500D01*
G01X329322Y-314459D02*
Y-319459D01*
G01X327865Y-314459D02*
X330779D01*
G01X335689Y-319459D02*
X333155D01*
Y-314459D01*
X335689D01*
G01X334675Y-316876D02*
X333155D01*
G01X338255Y-314459D02*
Y-319459D01*
X340789D01*
G01X344622Y-319626D02*
X344495Y-319542D01*
Y-319376D01*
X344622Y-319292D01*
X344749Y-319376D01*
Y-319542D01*
X344622Y-319626D01*
G01Y-317376D02*
X344495Y-317292D01*
Y-317126D01*
X344622Y-317042D01*
X344749Y-317126D01*
Y-317292D01*
X344622Y-317376D01*
G01X349405Y-321126D02*
X348772Y-320292D01*
X348455Y-319459D01*
Y-316126D01*
X348772Y-315292D01*
X349405Y-314459D01*
G01X354822D02*
X354315Y-314626D01*
X353935Y-315042D01*
X353682Y-315542D01*
X353492Y-316209D01*
X353429Y-316959D01*
X353492Y-317709D01*
X353682Y-318376D01*
X353935Y-318876D01*
X354315Y-319292D01*
X354822Y-319459D01*
X355329Y-319292D01*
X355709Y-318876D01*
X355962Y-318376D01*
X356152Y-317709D01*
X356215Y-316959D01*
X356152Y-316209D01*
X355962Y-315542D01*
X355709Y-315042D01*
X355329Y-314626D01*
X354822Y-314459D01*
G01X358529Y-318459D02*
X358909Y-319042D01*
X359415Y-319376D01*
X359985Y-319459D01*
X360492Y-319376D01*
X360999Y-318959D01*
X361315Y-318459D01*
X361379Y-317959D01*
X361252Y-317376D01*
X360809Y-316959D01*
X360365Y-316792D01*
X359795D01*
G01X360365D02*
X360745Y-316542D01*
X361062Y-316126D01*
X361189Y-315626D01*
X361062Y-315126D01*
X360745Y-314709D01*
X360175Y-314459D01*
X359605Y-314542D01*
X359035Y-314876D01*
G01X365339Y-321126D02*
X365972Y-320292D01*
X366289Y-319459D01*
Y-316126D01*
X365972Y-315292D01*
X365339Y-314459D01*
G01X368729Y-318459D02*
X369109Y-319042D01*
X369615Y-319376D01*
X370185Y-319459D01*
X370692Y-319376D01*
X371199Y-318959D01*
X371515Y-318459D01*
X371579Y-317959D01*
X371452Y-317376D01*
X371009Y-316959D01*
X370565Y-316792D01*
X369995D01*
G01X370565D02*
X370945Y-316542D01*
X371262Y-316126D01*
X371389Y-315626D01*
X371262Y-315126D01*
X370945Y-314709D01*
X370375Y-314459D01*
X369805Y-314542D01*
X369235Y-314876D01*
G01X374019Y-315292D02*
X374399Y-314792D01*
X374842Y-314542D01*
X375349Y-314459D01*
X375982Y-314626D01*
X376425Y-315042D01*
X376552Y-315542D01*
X376489Y-316042D01*
X376235Y-316459D01*
X374969Y-317292D01*
X374399Y-317876D01*
X374019Y-318709D01*
X373892Y-319459D01*
X376552D01*
G01X380195D02*
X380322Y-318376D01*
X380512Y-317459D01*
X380765Y-316626D01*
X381082Y-315709D01*
X381589Y-314459D01*
X379055D01*
G01X384599Y-317792D02*
X386245D01*
G01X389319Y-315292D02*
X389699Y-314792D01*
X390142Y-314542D01*
X390649Y-314459D01*
X391282Y-314626D01*
X391725Y-315042D01*
X391852Y-315542D01*
X391789Y-316042D01*
X391535Y-316459D01*
X390269Y-317292D01*
X389699Y-317876D01*
X389319Y-318709D01*
X389192Y-319459D01*
X391852D01*
G01X394229Y-318459D02*
X394609Y-319042D01*
X395115Y-319376D01*
X395685Y-319459D01*
X396192Y-319376D01*
X396699Y-318959D01*
X397015Y-318459D01*
X397079Y-317959D01*
X396952Y-317376D01*
X396509Y-316959D01*
X396065Y-316792D01*
X395495D01*
G01X396065D02*
X396445Y-316542D01*
X396762Y-316126D01*
X396889Y-315626D01*
X396762Y-315126D01*
X396445Y-314709D01*
X395875Y-314459D01*
X395305Y-314542D01*
X394735Y-314876D01*
G01X401482Y-319459D02*
Y-314459D01*
X399139Y-318042D01*
X402305D01*
G01X404429Y-318709D02*
X404809Y-319126D01*
X405252Y-319376D01*
X405822Y-319459D01*
X406392Y-319292D01*
X406835Y-318959D01*
X407152Y-318376D01*
X407215Y-317709D01*
X407089Y-317042D01*
X406772Y-316626D01*
X406329Y-316292D01*
X405885Y-316209D01*
X405442Y-316292D01*
X404872Y-316626D01*
X405062Y-314459D01*
X406772D01*
G01X414819Y-319459D02*
Y-314459D01*
X417225D01*
G01X416339Y-316876D02*
X414819D01*
G01X419539Y-319459D02*
X421122Y-314459D01*
X422705Y-319459D01*
G01X422135Y-317709D02*
X420109D01*
G01X424892Y-319459D02*
X427552Y-314459D01*
G01X424892D02*
X427552Y-319459D01*
G01X431322Y-319626D02*
X431195Y-319542D01*
Y-319376D01*
X431322Y-319292D01*
X431449Y-319376D01*
Y-319542D01*
X431322Y-319626D01*
G01Y-317376D02*
X431195Y-317292D01*
Y-317126D01*
X431322Y-317042D01*
X431449Y-317126D01*
Y-317292D01*
X431322Y-317376D01*
G01X436105Y-321126D02*
X435472Y-320292D01*
X435155Y-319459D01*
Y-316126D01*
X435472Y-315292D01*
X436105Y-314459D01*
G01X441522D02*
X441015Y-314626D01*
X440635Y-315042D01*
X440382Y-315542D01*
X440192Y-316209D01*
X440129Y-316959D01*
X440192Y-317709D01*
X440382Y-318376D01*
X440635Y-318876D01*
X441015Y-319292D01*
X441522Y-319459D01*
X442029Y-319292D01*
X442409Y-318876D01*
X442662Y-318376D01*
X442852Y-317709D01*
X442915Y-316959D01*
X442852Y-316209D01*
X442662Y-315542D01*
X442409Y-315042D01*
X442029Y-314626D01*
X441522Y-314459D01*
G01X445229Y-318459D02*
X445609Y-319042D01*
X446115Y-319376D01*
X446685Y-319459D01*
X447192Y-319376D01*
X447699Y-318959D01*
X448015Y-318459D01*
X448079Y-317959D01*
X447952Y-317376D01*
X447509Y-316959D01*
X447065Y-316792D01*
X446495D01*
G01X447065D02*
X447445Y-316542D01*
X447762Y-316126D01*
X447889Y-315626D01*
X447762Y-315126D01*
X447445Y-314709D01*
X446875Y-314459D01*
X446305Y-314542D01*
X445735Y-314876D01*
G01X452039Y-321126D02*
X452672Y-320292D01*
X452989Y-319459D01*
Y-316126D01*
X452672Y-315292D01*
X452039Y-314459D01*
G01X455429Y-318459D02*
X455809Y-319042D01*
X456315Y-319376D01*
X456885Y-319459D01*
X457392Y-319376D01*
X457899Y-318959D01*
X458215Y-318459D01*
X458279Y-317959D01*
X458152Y-317376D01*
X457709Y-316959D01*
X457265Y-316792D01*
X456695D01*
G01X457265D02*
X457645Y-316542D01*
X457962Y-316126D01*
X458089Y-315626D01*
X457962Y-315126D01*
X457645Y-314709D01*
X457075Y-314459D01*
X456505Y-314542D01*
X455935Y-314876D01*
G01X460845Y-318876D02*
X461289Y-319292D01*
X461795Y-319459D01*
X462302Y-319292D01*
X462745Y-318792D01*
X463062Y-318042D01*
X463189Y-317292D01*
Y-316376D01*
X463062Y-315626D01*
X462745Y-314959D01*
X462365Y-314626D01*
X461922Y-314459D01*
X461415Y-314626D01*
X461035Y-314959D01*
X460782Y-315459D01*
X460655Y-316126D01*
X460782Y-316709D01*
X461099Y-317292D01*
X461479Y-317626D01*
X461922Y-317709D01*
X462429Y-317542D01*
X462809Y-317126D01*
X463189Y-316376D01*
G01X466895Y-319459D02*
X467022Y-318376D01*
X467212Y-317459D01*
X467465Y-316626D01*
X467782Y-315709D01*
X468289Y-314459D01*
X465755D01*
G01X471299Y-317792D02*
X472945D01*
G01X475829Y-318459D02*
X476209Y-319042D01*
X476715Y-319376D01*
X477285Y-319459D01*
X477792Y-319376D01*
X478299Y-318959D01*
X478615Y-318459D01*
X478679Y-317959D01*
X478552Y-317376D01*
X478109Y-316959D01*
X477665Y-316792D01*
X477095D01*
G01X477665D02*
X478045Y-316542D01*
X478362Y-316126D01*
X478489Y-315626D01*
X478362Y-315126D01*
X478045Y-314709D01*
X477475Y-314459D01*
X476905Y-314542D01*
X476335Y-314876D01*
G01X481119Y-317376D02*
X481562Y-316792D01*
X481942Y-316459D01*
X482449Y-316292D01*
X482892Y-316459D01*
X483209Y-316792D01*
X483462Y-317292D01*
X483525Y-317876D01*
X483462Y-318376D01*
X483209Y-318876D01*
X482829Y-319292D01*
X482385Y-319459D01*
X481879Y-319292D01*
X481435Y-318792D01*
X481182Y-318042D01*
X481119Y-317209D01*
X481245Y-316126D01*
X481435Y-315542D01*
X481752Y-314959D01*
X482195Y-314542D01*
X482639Y-314459D01*
X483082Y-314626D01*
X483399Y-315042D01*
G01X487422Y-319459D02*
Y-314459D01*
X486662Y-315459D01*
G01Y-319459D02*
X488182D01*
G01X493282D02*
Y-314459D01*
X490939Y-318042D01*
X494105D01*
G01X317322Y-249459D02*
Y-324459D01*
X817322D01*
Y-249459D01*
X317322D01*
G01X512322D02*
Y-324459D01*
G01Y-299459D02*
X615322D01*
Y-274459D01*
G01X512322D02*
X615322D01*
G01X622829Y-309459D02*
Y-304459D01*
X624095D01*
X624602Y-304709D01*
X624982Y-305042D01*
X625299Y-305542D01*
X625552Y-306126D01*
X625615Y-306959D01*
X625552Y-307792D01*
X625299Y-308376D01*
X624982Y-308876D01*
X624602Y-309209D01*
X624095Y-309459D01*
X622829D01*
G01X627739D02*
X629322Y-304459D01*
X630905Y-309459D01*
G01X630335Y-307709D02*
X628309D01*
G01X634422Y-304459D02*
Y-309459D01*
G01X632965Y-304459D02*
X635879D01*
G01X640789Y-309459D02*
X638255D01*
Y-304459D01*
X640789D01*
G01X639775Y-306876D02*
X638255D01*
G01X644622Y-309626D02*
X644495Y-309542D01*
Y-309376D01*
X644622Y-309292D01*
X644749Y-309376D01*
Y-309542D01*
X644622Y-309626D01*
G01Y-307376D02*
X644495Y-307292D01*
Y-307126D01*
X644622Y-307042D01*
X644749Y-307126D01*
Y-307292D01*
X644622Y-307376D01*
G01X617322Y-249459D02*
Y-324459D01*
G01X615322Y-249459D02*
Y-324459D01*
G01X622955Y-284459D02*
Y-279459D01*
X624475D01*
X624982Y-279709D01*
X625362Y-280292D01*
X625489Y-280959D01*
X625362Y-281626D01*
X625045Y-282126D01*
X624475Y-282376D01*
X622955D01*
G01X628182Y-284626D02*
X630462Y-279459D01*
G01X632965Y-284459D02*
Y-279459D01*
X635879Y-284459D01*
Y-279459D01*
G01X639522Y-284626D02*
X639395Y-284542D01*
Y-284376D01*
X639522Y-284292D01*
X639649Y-284376D01*
Y-284542D01*
X639522Y-284626D01*
G01Y-282376D02*
X639395Y-282292D01*
Y-282126D01*
X639522Y-282042D01*
X639649Y-282126D01*
Y-282292D01*
X639522Y-282376D01*
G01X617322Y-299459D02*
X817322D01*
G01X622955Y-259459D02*
Y-254459D01*
X624475D01*
X624982Y-254709D01*
X625362Y-255292D01*
X625489Y-255959D01*
X625362Y-256626D01*
X625045Y-257126D01*
X624475Y-257376D01*
X622955D01*
G01X628055Y-259459D02*
Y-254459D01*
X629639D01*
X630145Y-254709D01*
X630462Y-255042D01*
X630589Y-255709D01*
X630462Y-256376D01*
X630082Y-256792D01*
X629639Y-257042D01*
X628055D01*
G01X629639D02*
X630589Y-259459D01*
G01X634422D02*
X633915Y-259376D01*
X633472Y-259042D01*
X633092Y-258542D01*
X632839Y-257959D01*
X632712Y-257292D01*
Y-256626D01*
X632839Y-255959D01*
X633092Y-255376D01*
X633472Y-254876D01*
X633915Y-254542D01*
X634422Y-254459D01*
X634929Y-254542D01*
X635372Y-254876D01*
X635752Y-255376D01*
X636005Y-255959D01*
X636132Y-256626D01*
Y-257292D01*
X636005Y-257959D01*
X635752Y-258542D01*
X635372Y-259042D01*
X634929Y-259376D01*
X634422Y-259459D01*
G01X638255Y-258459D02*
X638572Y-258959D01*
X638952Y-259292D01*
X639395Y-259459D01*
X639902Y-259292D01*
X640282Y-258959D01*
X640662Y-258459D01*
X640789Y-257792D01*
Y-254459D01*
G01X645889Y-259459D02*
X643355D01*
Y-254459D01*
X645889D01*
G01X644875Y-256876D02*
X643355D01*
G01X651115Y-254876D02*
X650735Y-254626D01*
X650292Y-254459D01*
X649785D01*
X649215Y-254709D01*
X648772Y-255126D01*
X648455Y-255626D01*
X648202Y-256459D01*
X648139Y-257209D01*
X648265Y-257959D01*
X648455Y-258459D01*
X648835Y-258959D01*
X649279Y-259292D01*
X649722Y-259459D01*
X650165D01*
X650609Y-259292D01*
X650989Y-259042D01*
X651305Y-258709D01*
G01X654822Y-254459D02*
Y-259459D01*
G01X653365Y-254459D02*
X656279D01*
G01X659922Y-259626D02*
X659795Y-259542D01*
Y-259376D01*
X659922Y-259292D01*
X660049Y-259376D01*
Y-259542D01*
X659922Y-259626D01*
G01Y-257376D02*
X659795Y-257292D01*
Y-257126D01*
X659922Y-257042D01*
X660049Y-257126D01*
Y-257292D01*
X659922Y-257376D01*
G01X617322Y-274459D02*
X817322D01*
G01X734955Y-301959D02*
Y-306959D01*
X737489D01*
G01X740562Y-301959D02*
X742082D01*
G01X741322D02*
Y-306959D01*
G01X740562D02*
X742082D01*
G01X746929Y-304292D02*
X747182Y-304042D01*
X747372Y-303626D01*
X747499Y-303042D01*
X747372Y-302542D01*
X747119Y-302209D01*
X746675Y-301959D01*
X744965D01*
Y-306959D01*
X747055D01*
X747499Y-306626D01*
X747752Y-306126D01*
X747879Y-305542D01*
X747752Y-304959D01*
X747372Y-304459D01*
X746929Y-304292D01*
X744965D01*
G01X751522Y-307126D02*
X751395Y-307042D01*
Y-306876D01*
X751522Y-306792D01*
X751649Y-306876D01*
Y-307042D01*
X751522Y-307126D01*
G01Y-304876D02*
X751395Y-304792D01*
Y-304626D01*
X751522Y-304542D01*
X751649Y-304626D01*
Y-304792D01*
X751522Y-304876D01*
G01X732322Y-299459D02*
Y-324459D01*
G01X779222Y-301959D02*
Y-306959D01*
G01X777765Y-301959D02*
X780679D01*
G01X784322Y-306959D02*
X783942Y-306876D01*
X783562Y-306542D01*
X783309Y-305959D01*
X783182Y-305292D01*
X783309Y-304626D01*
X783562Y-304042D01*
X783942Y-303709D01*
X784322Y-303626D01*
X784702Y-303709D01*
X785082Y-304042D01*
X785335Y-304626D01*
X785399Y-305292D01*
X785335Y-305959D01*
X785082Y-306542D01*
X784702Y-306876D01*
X784322Y-306959D01*
G01X789422D02*
X789042Y-306876D01*
X788662Y-306542D01*
X788409Y-305959D01*
X788282Y-305292D01*
X788409Y-304626D01*
X788662Y-304042D01*
X789042Y-303709D01*
X789422Y-303626D01*
X789802Y-303709D01*
X790182Y-304042D01*
X790435Y-304626D01*
X790499Y-305292D01*
X790435Y-305959D01*
X790182Y-306542D01*
X789802Y-306876D01*
X789422Y-306959D01*
G01X794522D02*
Y-301959D01*
G01X799622Y-307126D02*
X799495Y-307042D01*
Y-306876D01*
X799622Y-306792D01*
X799749Y-306876D01*
Y-307042D01*
X799622Y-307126D01*
G01Y-304876D02*
X799495Y-304792D01*
Y-304626D01*
X799622Y-304542D01*
X799749Y-304626D01*
Y-304792D01*
X799622Y-304876D01*
G01X775322Y-299459D02*
Y-324459D01*
G01Y-274459D02*
Y-299459D01*
G01X777955Y-281959D02*
Y-276959D01*
X779539D01*
X780045Y-277209D01*
X780362Y-277542D01*
X780489Y-278209D01*
X780362Y-278876D01*
X779982Y-279292D01*
X779539Y-279542D01*
X777955D01*
G01X779539D02*
X780489Y-281959D01*
G01X785589D02*
X783055D01*
Y-276959D01*
X785589D01*
G01X784575Y-279376D02*
X783055D01*
G01X787839Y-276959D02*
X789422Y-281959D01*
X791005Y-276959D01*
G01X794522Y-282126D02*
X794395Y-282042D01*
Y-281876D01*
X794522Y-281792D01*
X794649Y-281876D01*
Y-282042D01*
X794522Y-282126D01*
G01Y-279876D02*
X794395Y-279792D01*
Y-279626D01*
X794522Y-279542D01*
X794649Y-279626D01*
Y-279792D01*
X794522Y-279876D01*
G01X798082Y-326159D02*
X798162Y-326084D01*
X798222Y-325959D01*
X798262Y-325784D01*
X798222Y-325634D01*
X798142Y-325534D01*
X798002Y-325459D01*
X797462D01*
Y-326959D01*
X798122D01*
X798262Y-326859D01*
X798342Y-326709D01*
X798382Y-326534D01*
X798342Y-326359D01*
X798222Y-326209D01*
X798082Y-326159D01*
X797462D01*
G01X799482Y-326959D02*
Y-325959D01*
G01Y-326134D02*
X799402Y-326034D01*
X799282Y-325984D01*
X799142Y-325959D01*
X799002Y-326009D01*
X798882Y-326109D01*
X798802Y-326259D01*
X798762Y-326459D01*
X798802Y-326659D01*
X798882Y-326809D01*
X799002Y-326909D01*
X799142Y-326959D01*
X799282Y-326934D01*
X799402Y-326859D01*
X799482Y-326759D01*
G01X800022Y-326784D02*
X800122Y-326884D01*
X800262Y-326959D01*
X800382D01*
X800502Y-326909D01*
X800582Y-326834D01*
X800622Y-326734D01*
X800602Y-326584D01*
X800522Y-326509D01*
X800162Y-326359D01*
X800082Y-326184D01*
X800122Y-326059D01*
X800202Y-325984D01*
X800322Y-325959D01*
X800442Y-325984D01*
X800562Y-326059D01*
G01X801222Y-326284D02*
X801862D01*
X801802Y-326109D01*
X801702Y-326009D01*
X801562Y-325959D01*
X801422Y-325984D01*
X801302Y-326059D01*
X801222Y-326234D01*
X801182Y-326384D01*
Y-326534D01*
X801222Y-326684D01*
X801322Y-326834D01*
X801442Y-326934D01*
X801582Y-326959D01*
X801722Y-326909D01*
X801862Y-326759D01*
G01X802362Y-326959D02*
Y-325459D01*
G01Y-326209D02*
X802462Y-326059D01*
X802582Y-325984D01*
X802702Y-325959D01*
X802882Y-326009D01*
X803002Y-326109D01*
X803082Y-326284D01*
Y-326484D01*
X803042Y-326684D01*
X802962Y-326834D01*
X802822Y-326934D01*
X802702Y-326959D01*
X802582Y-326934D01*
X802462Y-326859D01*
X802362Y-326734D01*
G01X803922Y-326959D02*
X803802Y-326934D01*
X803682Y-326834D01*
X803602Y-326659D01*
X803562Y-326459D01*
X803602Y-326259D01*
X803682Y-326084D01*
X803802Y-325984D01*
X803922Y-325959D01*
X804042Y-325984D01*
X804162Y-326084D01*
X804242Y-326259D01*
X804262Y-326459D01*
X804242Y-326659D01*
X804162Y-326834D01*
X804042Y-326934D01*
X803922Y-326959D01*
G01X805482D02*
Y-325959D01*
G01Y-326134D02*
X805402Y-326034D01*
X805282Y-325984D01*
X805142Y-325959D01*
X805002Y-326009D01*
X804882Y-326109D01*
X804802Y-326259D01*
X804762Y-326459D01*
X804802Y-326659D01*
X804882Y-326809D01*
X805002Y-326909D01*
X805142Y-326959D01*
X805282Y-326934D01*
X805402Y-326859D01*
X805482Y-326759D01*
G01X806042Y-326959D02*
Y-325959D01*
G01Y-326159D02*
X806142Y-326059D01*
X806242Y-325984D01*
X806382Y-325959D01*
X806482Y-325984D01*
X806602Y-326059D01*
G01X807882Y-325459D02*
Y-326959D01*
G01Y-326734D02*
X807802Y-326859D01*
X807682Y-326934D01*
X807542Y-326959D01*
X807382Y-326909D01*
X807262Y-326784D01*
X807182Y-326634D01*
X807162Y-326459D01*
X807182Y-326284D01*
X807262Y-326134D01*
X807382Y-326009D01*
X807542Y-325959D01*
X807682Y-325984D01*
X807782Y-326034D01*
X807882Y-326134D01*
G01X809522Y-326959D02*
Y-325459D01*
X810022D01*
X810182Y-325534D01*
X810282Y-325634D01*
X810322Y-325834D01*
X810282Y-326034D01*
X810162Y-326159D01*
X810022Y-326234D01*
X809522D01*
G01X810022D02*
X810322Y-326959D01*
G01X810822Y-326284D02*
X811462D01*
X811402Y-326109D01*
X811302Y-326009D01*
X811162Y-325959D01*
X811022Y-325984D01*
X810902Y-326059D01*
X810822Y-326234D01*
X810782Y-326384D01*
Y-326534D01*
X810822Y-326684D01*
X810922Y-326834D01*
X811042Y-326934D01*
X811182Y-326959D01*
X811322Y-326909D01*
X811462Y-326759D01*
G01X811962Y-325959D02*
X812322Y-326959D01*
X812682Y-325959D01*
G01X813522Y-327009D02*
X813482Y-326984D01*
Y-326934D01*
X813522Y-326909D01*
X813562Y-326934D01*
Y-326984D01*
X813522Y-327009D01*
G01X814682Y-326959D02*
X814722Y-326634D01*
X814782Y-326359D01*
X814862Y-326109D01*
X814962Y-325834D01*
X815122Y-325459D01*
X814322D01*
G01X816082Y-326159D02*
X816162Y-326084D01*
X816222Y-325959D01*
X816262Y-325784D01*
X816222Y-325634D01*
X816142Y-325534D01*
X816002Y-325459D01*
X815462D01*
Y-326959D01*
X816122D01*
X816262Y-326859D01*
X816342Y-326709D01*
X816382Y-326534D01*
X816342Y-326359D01*
X816222Y-326209D01*
X816082Y-326159D01*
X815462D01*
G01X-320500Y-470483D02*
Y2626000D01*
X2967000D01*
Y-470483D01*
X-320500D01*
G01X331395Y-304184D02*
X330925Y-303869D01*
X330377Y-303659D01*
X329750D01*
X329045Y-303974D01*
X328497Y-304499D01*
X328105Y-305129D01*
X327792Y-306179D01*
X327714Y-307124D01*
X327870Y-308069D01*
X328105Y-308699D01*
X328575Y-309329D01*
X329124Y-309749D01*
X329672Y-309959D01*
X330220D01*
X330769Y-309749D01*
X331239Y-309434D01*
X331630Y-309014D01*
G01X335032Y-303659D02*
X336912D01*
G01X335972D02*
Y-309959D01*
G01X335032D02*
X336912D01*
G01X342272Y-303659D02*
Y-309959D01*
G01X340470Y-303659D02*
X344074D01*
G01X348572Y-309959D02*
Y-307124D01*
X347005Y-303659D01*
G01X350139D02*
X348572Y-307124D01*
G01X359449Y-308699D02*
X359919Y-309434D01*
X360545Y-309854D01*
X361250Y-309959D01*
X361877Y-309854D01*
X362504Y-309329D01*
X362895Y-308699D01*
X362974Y-308069D01*
X362817Y-307334D01*
X362269Y-306809D01*
X361720Y-306599D01*
X361015D01*
G01X361720D02*
X362190Y-306284D01*
X362582Y-305759D01*
X362739Y-305129D01*
X362582Y-304499D01*
X362190Y-303974D01*
X361485Y-303659D01*
X360780Y-303764D01*
X360075Y-304184D01*
G01X365749Y-308699D02*
X366219Y-309434D01*
X366845Y-309854D01*
X367550Y-309959D01*
X368177Y-309854D01*
X368804Y-309329D01*
X369195Y-308699D01*
X369274Y-308069D01*
X369117Y-307334D01*
X368569Y-306809D01*
X368020Y-306599D01*
X367315D01*
G01X368020D02*
X368490Y-306284D01*
X368882Y-305759D01*
X369039Y-305129D01*
X368882Y-304499D01*
X368490Y-303974D01*
X367785Y-303659D01*
X367080Y-303764D01*
X366375Y-304184D01*
G01X372049Y-308699D02*
X372519Y-309434D01*
X373145Y-309854D01*
X373850Y-309959D01*
X374477Y-309854D01*
X375104Y-309329D01*
X375495Y-308699D01*
X375574Y-308069D01*
X375417Y-307334D01*
X374869Y-306809D01*
X374320Y-306599D01*
X373615D01*
G01X374320D02*
X374790Y-306284D01*
X375182Y-305759D01*
X375339Y-305129D01*
X375182Y-304499D01*
X374790Y-303974D01*
X374085Y-303659D01*
X373380Y-303764D01*
X372675Y-304184D01*
G01X379915Y-309959D02*
X380072Y-308594D01*
X380307Y-307439D01*
X380620Y-306389D01*
X381012Y-305234D01*
X381639Y-303659D01*
X378505D01*
G01X386215Y-309959D02*
X386372Y-308594D01*
X386607Y-307439D01*
X386920Y-306389D01*
X387312Y-305234D01*
X387939Y-303659D01*
X384805D01*
G01X392515Y-311114D02*
X392829Y-309749D01*
G01X398972Y-303659D02*
Y-309959D01*
G01X397170Y-303659D02*
X400774D01*
G01X403314Y-309959D02*
X405272Y-303659D01*
X407230Y-309959D01*
G01X406525Y-307754D02*
X404019D01*
G01X410632Y-303659D02*
X412512D01*
G01X411572D02*
Y-309959D01*
G01X410632D02*
X412512D01*
G01X415522Y-303659D02*
X416619Y-309959D01*
X417872Y-303659D01*
X419125Y-309959D01*
X420222Y-303659D01*
G01X422214Y-309959D02*
X424172Y-303659D01*
X426130Y-309959D01*
G01X425425Y-307754D02*
X422919D01*
G01X428670Y-309959D02*
Y-303659D01*
X432274Y-309959D01*
Y-303659D01*
G01X442680Y-312059D02*
X441897Y-311009D01*
X441505Y-309959D01*
Y-305759D01*
X441897Y-304709D01*
X442680Y-303659D01*
G01X454105Y-309959D02*
Y-303659D01*
X456064D01*
X456690Y-303974D01*
X457082Y-304394D01*
X457239Y-305234D01*
X457082Y-306074D01*
X456612Y-306599D01*
X456064Y-306914D01*
X454105D01*
G01X456064D02*
X457239Y-309959D01*
G01X461972Y-310169D02*
X461815Y-310064D01*
Y-309854D01*
X461972Y-309749D01*
X462129Y-309854D01*
Y-310064D01*
X461972Y-310169D01*
G01X468272Y-309959D02*
X467645Y-309854D01*
X467097Y-309434D01*
X466627Y-308804D01*
X466314Y-308069D01*
X466157Y-307229D01*
Y-306389D01*
X466314Y-305549D01*
X466627Y-304814D01*
X467097Y-304184D01*
X467645Y-303764D01*
X468272Y-303659D01*
X468899Y-303764D01*
X469447Y-304184D01*
X469917Y-304814D01*
X470230Y-305549D01*
X470387Y-306389D01*
Y-307229D01*
X470230Y-308069D01*
X469917Y-308804D01*
X469447Y-309434D01*
X468899Y-309854D01*
X468272Y-309959D01*
G01X474572Y-310169D02*
X474415Y-310064D01*
Y-309854D01*
X474572Y-309749D01*
X474729Y-309854D01*
Y-310064D01*
X474572Y-310169D01*
G01X482595Y-304184D02*
X482125Y-303869D01*
X481577Y-303659D01*
X480950D01*
X480245Y-303974D01*
X479697Y-304499D01*
X479305Y-305129D01*
X478992Y-306179D01*
X478914Y-307124D01*
X479070Y-308069D01*
X479305Y-308699D01*
X479775Y-309329D01*
X480324Y-309749D01*
X480872Y-309959D01*
X481420D01*
X481969Y-309749D01*
X482439Y-309434D01*
X482830Y-309014D01*
G01X487172Y-310169D02*
X487015Y-310064D01*
Y-309854D01*
X487172Y-309749D01*
X487329Y-309854D01*
Y-310064D01*
X487172Y-310169D01*
G01X493864Y-312059D02*
X494647Y-311009D01*
X495039Y-309959D01*
Y-305759D01*
X494647Y-304709D01*
X493864Y-303659D01*
G01X330142Y-296809D02*
X331709D01*
Y-298699D01*
X331239Y-299329D01*
X330690Y-299749D01*
X329907Y-299959D01*
X329124Y-299749D01*
X328575Y-299329D01*
X328105Y-298699D01*
X327792Y-297964D01*
X327635Y-297124D01*
Y-296389D01*
X327792Y-295759D01*
X328105Y-295024D01*
X328575Y-294394D01*
X329045Y-293974D01*
X329672Y-293659D01*
X330220D01*
X330847Y-293869D01*
X331317Y-294289D01*
G01X334249Y-293659D02*
Y-298174D01*
X334562Y-299119D01*
X335189Y-299749D01*
X335972Y-299959D01*
X336755Y-299749D01*
X337382Y-299119D01*
X337695Y-298174D01*
Y-293659D01*
G01X341332D02*
X343212D01*
G01X342272D02*
Y-299959D01*
G01X341332D02*
X343212D01*
G01X346927Y-299119D02*
X347554Y-299644D01*
X348259Y-299959D01*
X348885D01*
X349512Y-299644D01*
X349982Y-299119D01*
X350217Y-298384D01*
X350060Y-297649D01*
X349669Y-297019D01*
X348964Y-296599D01*
X348024Y-296389D01*
X347475Y-295969D01*
X347240Y-295234D01*
X347397Y-294499D01*
X347789Y-293974D01*
X348337Y-293659D01*
X348885D01*
X349434Y-293869D01*
X349904Y-294394D01*
G01X353227Y-299959D02*
Y-293659D01*
G01X356517D02*
Y-299959D01*
G01Y-296809D02*
X353227D01*
G01X359214Y-299959D02*
X361172Y-293659D01*
X363130Y-299959D01*
G01X362425Y-297754D02*
X359919D01*
G01X365670Y-299959D02*
Y-293659D01*
X369274Y-299959D01*
Y-293659D01*
G01X378349Y-299959D02*
Y-293659D01*
X379915D01*
X380542Y-293974D01*
X381012Y-294394D01*
X381404Y-295024D01*
X381717Y-295759D01*
X381795Y-296809D01*
X381717Y-297859D01*
X381404Y-298594D01*
X381012Y-299224D01*
X380542Y-299644D01*
X379915Y-299959D01*
X378349D01*
G01X385432Y-293659D02*
X387312D01*
G01X386372D02*
Y-299959D01*
G01X385432D02*
X387312D01*
G01X391027Y-299119D02*
X391654Y-299644D01*
X392359Y-299959D01*
X392985D01*
X393612Y-299644D01*
X394082Y-299119D01*
X394317Y-298384D01*
X394160Y-297649D01*
X393769Y-297019D01*
X393064Y-296599D01*
X392124Y-296389D01*
X391575Y-295969D01*
X391340Y-295234D01*
X391497Y-294499D01*
X391889Y-293974D01*
X392437Y-293659D01*
X392985D01*
X393534Y-293869D01*
X394004Y-294394D01*
G01X398972Y-293659D02*
Y-299959D01*
G01X397170Y-293659D02*
X400774D01*
G01X405272Y-300169D02*
X405115Y-300064D01*
Y-299854D01*
X405272Y-299749D01*
X405429Y-299854D01*
Y-300064D01*
X405272Y-300169D01*
G01X411415Y-301114D02*
X411729Y-299749D01*
G01X417872Y-293659D02*
Y-299959D01*
G01X416070Y-293659D02*
X419674D01*
G01X422214Y-299959D02*
X424172Y-293659D01*
X426130Y-299959D01*
G01X425425Y-297754D02*
X422919D01*
G01X430472Y-299959D02*
X429845Y-299854D01*
X429297Y-299434D01*
X428827Y-298804D01*
X428514Y-298069D01*
X428357Y-297229D01*
Y-296389D01*
X428514Y-295549D01*
X428827Y-294814D01*
X429297Y-294184D01*
X429845Y-293764D01*
X430472Y-293659D01*
X431099Y-293764D01*
X431647Y-294184D01*
X432117Y-294814D01*
X432430Y-295549D01*
X432587Y-296389D01*
Y-297229D01*
X432430Y-298069D01*
X432117Y-298804D01*
X431647Y-299434D01*
X431099Y-299854D01*
X430472Y-299959D01*
G01X436772D02*
Y-297124D01*
X435205Y-293659D01*
G01X438339D02*
X436772Y-297124D01*
G01X441349Y-293659D02*
Y-298174D01*
X441662Y-299119D01*
X442289Y-299749D01*
X443072Y-299959D01*
X443855Y-299749D01*
X444482Y-299119D01*
X444795Y-298174D01*
Y-293659D01*
G01X447414Y-299959D02*
X449372Y-293659D01*
X451330Y-299959D01*
G01X450625Y-297754D02*
X448119D01*
G01X453870Y-299959D02*
Y-293659D01*
X457474Y-299959D01*
Y-293659D01*
G01X327870Y-289959D02*
Y-283659D01*
X331474Y-289959D01*
Y-283659D01*
G01X335972Y-289959D02*
X335345Y-289854D01*
X334797Y-289434D01*
X334327Y-288804D01*
X334014Y-288069D01*
X333857Y-287229D01*
Y-286389D01*
X334014Y-285549D01*
X334327Y-284814D01*
X334797Y-284184D01*
X335345Y-283764D01*
X335972Y-283659D01*
X336599Y-283764D01*
X337147Y-284184D01*
X337617Y-284814D01*
X337930Y-285549D01*
X338087Y-286389D01*
Y-287229D01*
X337930Y-288069D01*
X337617Y-288804D01*
X337147Y-289434D01*
X336599Y-289854D01*
X335972Y-289959D01*
G01X342272Y-290169D02*
X342115Y-290064D01*
Y-289854D01*
X342272Y-289749D01*
X342429Y-289854D01*
Y-290064D01*
X342272Y-290169D01*
G01X347084Y-284709D02*
X347554Y-284079D01*
X348102Y-283764D01*
X348729Y-283659D01*
X349512Y-283869D01*
X350060Y-284394D01*
X350217Y-285024D01*
X350139Y-285654D01*
X349825Y-286179D01*
X348259Y-287229D01*
X347554Y-287964D01*
X347084Y-289014D01*
X346927Y-289959D01*
X350217D01*
G01X354872D02*
Y-283659D01*
X353932Y-284919D01*
G01Y-289959D02*
X355812D01*
G01X361172D02*
Y-283659D01*
X360232Y-284919D01*
G01Y-289959D02*
X362112D01*
G01X367315Y-291114D02*
X367629Y-289749D01*
G01X371422Y-283659D02*
X372519Y-289959D01*
X373772Y-283659D01*
X375025Y-289959D01*
X376122Y-283659D01*
G01X381639Y-289959D02*
X378505D01*
Y-283659D01*
X381639D01*
G01X380385Y-286704D02*
X378505D01*
G01X384570Y-289959D02*
Y-283659D01*
X388174Y-289959D01*
Y-283659D01*
G01X391027Y-289959D02*
Y-283659D01*
G01X394317D02*
Y-289959D01*
G01Y-286809D02*
X391027D01*
G01X397249Y-283659D02*
Y-288174D01*
X397562Y-289119D01*
X398189Y-289749D01*
X398972Y-289959D01*
X399755Y-289749D01*
X400382Y-289119D01*
X400695Y-288174D01*
Y-283659D01*
G01X403314Y-289959D02*
X405272Y-283659D01*
X407230Y-289959D01*
G01X406525Y-287754D02*
X404019D01*
G01X416384Y-284709D02*
X416854Y-284079D01*
X417402Y-283764D01*
X418029Y-283659D01*
X418812Y-283869D01*
X419360Y-284394D01*
X419517Y-285024D01*
X419439Y-285654D01*
X419125Y-286179D01*
X417559Y-287229D01*
X416854Y-287964D01*
X416384Y-289014D01*
X416227Y-289959D01*
X419517D01*
G01X422370D02*
Y-283659D01*
X425974Y-289959D01*
Y-283659D01*
G01X428749Y-289959D02*
Y-283659D01*
X430315D01*
X430942Y-283974D01*
X431412Y-284394D01*
X431804Y-285024D01*
X432117Y-285759D01*
X432195Y-286809D01*
X432117Y-287859D01*
X431804Y-288594D01*
X431412Y-289224D01*
X430942Y-289644D01*
X430315Y-289959D01*
X428749D01*
G01X441505D02*
Y-283659D01*
X443464D01*
X444090Y-283974D01*
X444482Y-284394D01*
X444639Y-285234D01*
X444482Y-286074D01*
X444012Y-286599D01*
X443464Y-286914D01*
X441505D01*
G01X443464D02*
X444639Y-289959D01*
G01X447649D02*
Y-283659D01*
X449215D01*
X449842Y-283974D01*
X450312Y-284394D01*
X450704Y-285024D01*
X451017Y-285759D01*
X451095Y-286809D01*
X451017Y-287859D01*
X450704Y-288594D01*
X450312Y-289224D01*
X449842Y-289644D01*
X449215Y-289959D01*
X447649D01*
G01X455672Y-290169D02*
X455515Y-290064D01*
Y-289854D01*
X455672Y-289749D01*
X455829Y-289854D01*
Y-290064D01*
X455672Y-290169D01*
G01X351972Y-279259D02*
X349452Y-278842D01*
X347247Y-277176D01*
X345357Y-274676D01*
X344097Y-271759D01*
X343467Y-268426D01*
Y-265092D01*
X344097Y-261759D01*
X345357Y-258842D01*
X347247Y-256343D01*
X349452Y-254676D01*
X351972Y-254259D01*
X354492Y-254676D01*
X356697Y-256343D01*
X358587Y-258842D01*
X359847Y-261759D01*
X360477Y-265092D01*
Y-268426D01*
X359847Y-271759D01*
X358587Y-274676D01*
X356697Y-277176D01*
X354492Y-278842D01*
X351972Y-279259D01*
G01X354492Y-272592D02*
X358272Y-279259D01*
G01X371817Y-262593D02*
Y-274259D01*
X373077Y-277176D01*
X374967Y-278842D01*
X377172Y-279259D01*
X379377Y-278842D01*
X381267Y-277176D01*
X382527Y-274259D01*
G01Y-279259D02*
Y-262593D01*
G01X408042Y-279259D02*
Y-262593D01*
G01Y-265509D02*
X406782Y-263843D01*
X404892Y-263009D01*
X402687Y-262593D01*
X400482Y-263426D01*
X398592Y-265092D01*
X397332Y-267593D01*
X396702Y-270926D01*
X397332Y-274259D01*
X398592Y-276760D01*
X400482Y-278426D01*
X402687Y-279259D01*
X404892Y-278842D01*
X406782Y-277593D01*
X408042Y-275926D01*
G01X422217Y-279259D02*
Y-262593D01*
G01Y-266759D02*
X423477Y-264676D01*
X425367Y-263009D01*
X427887Y-262593D01*
X430092Y-263009D01*
X431982Y-264676D01*
X432927Y-267593D01*
Y-279259D01*
G01X452772Y-254259D02*
Y-279259D01*
G01X448362Y-262593D02*
X457182D01*
G01X483642Y-279259D02*
Y-262593D01*
G01Y-265509D02*
X482382Y-263843D01*
X480492Y-263009D01*
X478287Y-262593D01*
X476082Y-263426D01*
X474192Y-265092D01*
X472932Y-267593D01*
X472302Y-270926D01*
X472932Y-274259D01*
X474192Y-276760D01*
X476082Y-278426D01*
X478287Y-279259D01*
X480492Y-278842D01*
X482382Y-277593D01*
X483642Y-275926D01*
G01X523322Y-258959D02*
Y-266959D01*
X527322D01*
G01X535122D02*
Y-261626D01*
G01Y-262559D02*
X534722Y-262026D01*
X534122Y-261759D01*
X533422Y-261626D01*
X532722Y-261892D01*
X532122Y-262426D01*
X531722Y-263226D01*
X531522Y-264292D01*
X531722Y-265359D01*
X532122Y-266159D01*
X532722Y-266692D01*
X533422Y-266959D01*
X534122Y-266826D01*
X534722Y-266426D01*
X535122Y-265893D01*
G01X539222Y-269359D02*
X539822Y-269626D01*
X540622Y-269359D01*
X541122Y-268826D01*
X541522Y-268159D01*
X542122Y-266026D01*
X543422Y-261626D01*
G01X540222D02*
X542122Y-266026D01*
G01X547822Y-263359D02*
X551022D01*
X550722Y-262426D01*
X550222Y-261892D01*
X549522Y-261626D01*
X548822Y-261759D01*
X548222Y-262159D01*
X547822Y-263092D01*
X547622Y-263893D01*
Y-264692D01*
X547822Y-265492D01*
X548322Y-266292D01*
X548922Y-266826D01*
X549622Y-266959D01*
X550322Y-266692D01*
X551022Y-265893D01*
G01X555922Y-266959D02*
Y-261626D01*
G01Y-262692D02*
X556422Y-262159D01*
X556922Y-261759D01*
X557622Y-261626D01*
X558122Y-261759D01*
X558722Y-262159D01*
G01X542022Y-316959D02*
Y-308959D01*
X546622Y-316959D01*
Y-308959D01*
G01X552322Y-311626D02*
Y-316959D01*
G01Y-309492D02*
X552122Y-309359D01*
Y-309092D01*
X552322Y-308959D01*
X552522Y-309092D01*
Y-309359D01*
X552322Y-309492D01*
G01X558622Y-316959D02*
Y-311626D01*
G01Y-312959D02*
X559022Y-312292D01*
X559622Y-311759D01*
X560422Y-311626D01*
X561122Y-311759D01*
X561722Y-312292D01*
X562022Y-313226D01*
Y-316959D01*
G01X570122D02*
Y-311626D01*
G01Y-312559D02*
X569722Y-312026D01*
X569122Y-311759D01*
X568422Y-311626D01*
X567722Y-311892D01*
X567122Y-312426D01*
X566722Y-313226D01*
X566522Y-314292D01*
X566722Y-315359D01*
X567122Y-316159D01*
X567722Y-316692D01*
X568422Y-316959D01*
X569122Y-316826D01*
X569722Y-316426D01*
X570122Y-315893D01*
G01X555622Y-283959D02*
X558022D01*
G01X556822D02*
Y-291959D01*
G01X555622D02*
X558022D01*
G01X562522D02*
Y-283959D01*
X567122Y-291959D01*
Y-283959D01*
G01X570922Y-285292D02*
X571522Y-284492D01*
X572222Y-284092D01*
X573022Y-283959D01*
X574022Y-284226D01*
X574722Y-284892D01*
X574922Y-285692D01*
X574822Y-286493D01*
X574422Y-287159D01*
X572422Y-288492D01*
X571522Y-289426D01*
X570922Y-290759D01*
X570722Y-291959D01*
X574922D01*
G01X578022Y-266959D02*
Y-258959D01*
X574322Y-264692D01*
X579322D01*
G01X649922Y-310292D02*
X650522Y-309492D01*
X651222Y-309092D01*
X652022Y-308959D01*
X653022Y-309226D01*
X653722Y-309892D01*
X653922Y-310692D01*
X653822Y-311493D01*
X653422Y-312159D01*
X651422Y-313492D01*
X650522Y-314426D01*
X649922Y-315759D01*
X649722Y-316959D01*
X653922D01*
G01X659822Y-308959D02*
X659022Y-309226D01*
X658422Y-309892D01*
X658022Y-310692D01*
X657722Y-311759D01*
X657622Y-312959D01*
X657722Y-314159D01*
X658022Y-315226D01*
X658422Y-316026D01*
X659022Y-316692D01*
X659822Y-316959D01*
X660622Y-316692D01*
X661222Y-316026D01*
X661622Y-315226D01*
X661922Y-314159D01*
X662022Y-312959D01*
X661922Y-311759D01*
X661622Y-310692D01*
X661222Y-309892D01*
X660622Y-309226D01*
X659822Y-308959D01*
G01X665922Y-310292D02*
X666522Y-309492D01*
X667222Y-309092D01*
X668022Y-308959D01*
X669022Y-309226D01*
X669722Y-309892D01*
X669922Y-310692D01*
X669822Y-311493D01*
X669422Y-312159D01*
X667422Y-313492D01*
X666522Y-314426D01*
X665922Y-315759D01*
X665722Y-316959D01*
X669922D01*
G01X673922Y-310292D02*
X674522Y-309492D01*
X675222Y-309092D01*
X676022Y-308959D01*
X677022Y-309226D01*
X677722Y-309892D01*
X677922Y-310692D01*
X677822Y-311493D01*
X677422Y-312159D01*
X675422Y-313492D01*
X674522Y-314426D01*
X673922Y-315759D01*
X673722Y-316959D01*
X677922D01*
G01X682022Y-317226D02*
X685622Y-308959D01*
G01X691822Y-316959D02*
Y-308959D01*
X690622Y-310559D01*
G01Y-316959D02*
X693022D01*
G01X697922Y-310292D02*
X698522Y-309492D01*
X699222Y-309092D01*
X700022Y-308959D01*
X701022Y-309226D01*
X701722Y-309892D01*
X701922Y-310692D01*
X701822Y-311493D01*
X701422Y-312159D01*
X699422Y-313492D01*
X698522Y-314426D01*
X697922Y-315759D01*
X697722Y-316959D01*
X701922D01*
G01X706022Y-317226D02*
X709622Y-308959D01*
G01X715822D02*
X715022Y-309226D01*
X714422Y-309892D01*
X714022Y-310692D01*
X713722Y-311759D01*
X713622Y-312959D01*
X713722Y-314159D01*
X714022Y-315226D01*
X714422Y-316026D01*
X715022Y-316692D01*
X715822Y-316959D01*
X716622Y-316692D01*
X717222Y-316026D01*
X717622Y-315226D01*
X717922Y-314159D01*
X718022Y-312959D01*
X717922Y-311759D01*
X717622Y-310692D01*
X717222Y-309892D01*
X716622Y-309226D01*
X715822Y-308959D01*
G01X722122Y-316026D02*
X722822Y-316692D01*
X723622Y-316959D01*
X724422Y-316692D01*
X725122Y-315893D01*
X725622Y-314692D01*
X725822Y-313492D01*
Y-312026D01*
X725622Y-310826D01*
X725122Y-309759D01*
X724522Y-309226D01*
X723822Y-308959D01*
X723022Y-309226D01*
X722422Y-309759D01*
X722022Y-310559D01*
X721822Y-311626D01*
X722022Y-312559D01*
X722522Y-313492D01*
X723122Y-314026D01*
X723822Y-314159D01*
X724622Y-313893D01*
X725222Y-313226D01*
X725822Y-312026D01*
G01X649622Y-291959D02*
Y-283959D01*
X651622D01*
X652422Y-284359D01*
X653022Y-284892D01*
X653522Y-285692D01*
X653922Y-286626D01*
X654022Y-287959D01*
X653922Y-289292D01*
X653522Y-290226D01*
X653022Y-291026D01*
X652422Y-291559D01*
X651622Y-291959D01*
X649622D01*
G01X657322D02*
X659822Y-283959D01*
X662322Y-291959D01*
G01X661422Y-289159D02*
X658222D01*
G01X667822Y-283959D02*
X667022Y-284226D01*
X666422Y-284892D01*
X666022Y-285692D01*
X665722Y-286759D01*
X665622Y-287959D01*
X665722Y-289159D01*
X666022Y-290226D01*
X666422Y-291026D01*
X667022Y-291692D01*
X667822Y-291959D01*
X668622Y-291692D01*
X669222Y-291026D01*
X669622Y-290226D01*
X669922Y-289159D01*
X670022Y-287959D01*
X669922Y-286759D01*
X669622Y-285692D01*
X669222Y-284892D01*
X668622Y-284226D01*
X667822Y-283959D01*
G01X673922Y-291959D02*
Y-283959D01*
X677722D01*
G01X676322Y-287826D02*
X673922D01*
G01X683822Y-283959D02*
X683022Y-284226D01*
X682422Y-284892D01*
X682022Y-285692D01*
X681722Y-286759D01*
X681622Y-287959D01*
X681722Y-289159D01*
X682022Y-290226D01*
X682422Y-291026D01*
X683022Y-291692D01*
X683822Y-291959D01*
X684622Y-291692D01*
X685222Y-291026D01*
X685622Y-290226D01*
X685922Y-289159D01*
X686022Y-287959D01*
X685922Y-286759D01*
X685622Y-285692D01*
X685222Y-284892D01*
X684622Y-284226D01*
X683822Y-283959D01*
G01X691822D02*
Y-291959D01*
G01X689522Y-283959D02*
X694122D01*
G01X697922Y-291959D02*
Y-283959D01*
X701722D01*
G01X700322Y-287826D02*
X697922D01*
G01X708622Y-287692D02*
X709022Y-287292D01*
X709322Y-286626D01*
X709522Y-285692D01*
X709322Y-284892D01*
X708922Y-284359D01*
X708222Y-283959D01*
X705522D01*
Y-291959D01*
X708822D01*
X709522Y-291426D01*
X709922Y-290626D01*
X710122Y-289692D01*
X709922Y-288759D01*
X709322Y-287959D01*
X708622Y-287692D01*
X705522D01*
G01X713922Y-288626D02*
X714622Y-287692D01*
X715222Y-287159D01*
X716022Y-286892D01*
X716722Y-287159D01*
X717222Y-287692D01*
X717622Y-288492D01*
X717722Y-289426D01*
X717622Y-290226D01*
X717222Y-291026D01*
X716622Y-291692D01*
X715922Y-291959D01*
X715122Y-291692D01*
X714422Y-290893D01*
X714022Y-289692D01*
X713922Y-288359D01*
X714122Y-286626D01*
X714422Y-285692D01*
X714922Y-284759D01*
X715622Y-284092D01*
X716322Y-283959D01*
X717022Y-284226D01*
X717522Y-284892D01*
G01X721622Y-291959D02*
Y-283959D01*
X723622D01*
X724422Y-284359D01*
X725022Y-284892D01*
X725522Y-285692D01*
X725922Y-286626D01*
X726022Y-287959D01*
X725922Y-289292D01*
X725522Y-290226D01*
X725022Y-291026D01*
X724422Y-291559D01*
X723622Y-291959D01*
X721622D01*
G01X731822Y-283959D02*
X731022Y-284226D01*
X730422Y-284892D01*
X730022Y-285692D01*
X729722Y-286759D01*
X729622Y-287959D01*
X729722Y-289159D01*
X730022Y-290226D01*
X730422Y-291026D01*
X731022Y-291692D01*
X731822Y-291959D01*
X732622Y-291692D01*
X733222Y-291026D01*
X733622Y-290226D01*
X733922Y-289159D01*
X734022Y-287959D01*
X733922Y-286759D01*
X733622Y-285692D01*
X733222Y-284892D01*
X732622Y-284226D01*
X731822Y-283959D01*
G01X649862Y-270000D02*
Y-263700D01*
X652838D01*
G01X651742Y-266745D02*
X649862D01*
G01X657650Y-263700D02*
X657023Y-263910D01*
X656553Y-264435D01*
X656240Y-265065D01*
X656005Y-265905D01*
X655927Y-266850D01*
X656005Y-267795D01*
X656240Y-268635D01*
X656553Y-269265D01*
X657023Y-269790D01*
X657650Y-270000D01*
X658277Y-269790D01*
X658747Y-269265D01*
X659060Y-268635D01*
X659295Y-267795D01*
X659373Y-266850D01*
X659295Y-265905D01*
X659060Y-265065D01*
X658747Y-264435D01*
X658277Y-263910D01*
X657650Y-263700D01*
G01X663950D02*
Y-270000D01*
G01X662148Y-263700D02*
X665752D01*
G01X667900Y-272100D02*
X672600D01*
G01X674983Y-270000D02*
Y-263700D01*
X676863D01*
X677490Y-264015D01*
X677960Y-264750D01*
X678117Y-265590D01*
X677960Y-266430D01*
X677568Y-267060D01*
X676863Y-267375D01*
X674983D01*
G01X684573Y-264225D02*
X684103Y-263910D01*
X683555Y-263700D01*
X682928D01*
X682223Y-264015D01*
X681675Y-264540D01*
X681283Y-265170D01*
X680970Y-266220D01*
X680892Y-267165D01*
X681048Y-268110D01*
X681283Y-268740D01*
X681753Y-269370D01*
X682302Y-269790D01*
X682850Y-270000D01*
X683398D01*
X683947Y-269790D01*
X684417Y-269475D01*
X684808Y-269055D01*
G01X689777Y-266640D02*
X690090Y-266325D01*
X690325Y-265800D01*
X690482Y-265065D01*
X690325Y-264435D01*
X690012Y-264015D01*
X689463Y-263700D01*
X687348D01*
Y-270000D01*
X689933D01*
X690482Y-269580D01*
X690795Y-268950D01*
X690952Y-268215D01*
X690795Y-267480D01*
X690325Y-266850D01*
X689777Y-266640D01*
X687348D01*
G01X693100Y-272100D02*
X697800D01*
G01X700262Y-270000D02*
Y-263700D01*
X703238D01*
G01X702142Y-266745D02*
X700262D01*
G01X706092Y-270000D02*
X708050Y-263700D01*
X710008Y-270000D01*
G01X709303Y-267795D02*
X706797D01*
G01X712548Y-270000D02*
Y-263700D01*
X716152Y-270000D01*
Y-263700D01*
G01X718300Y-272100D02*
X723000D01*
G01X727577Y-266640D02*
X727890Y-266325D01*
X728125Y-265800D01*
X728282Y-265065D01*
X728125Y-264435D01*
X727812Y-264015D01*
X727263Y-263700D01*
X725148D01*
Y-270000D01*
X727733D01*
X728282Y-269580D01*
X728595Y-268950D01*
X728752Y-268215D01*
X728595Y-267480D01*
X728125Y-266850D01*
X727577Y-266640D01*
X725148D01*
G01X733250Y-270000D02*
X732623Y-269895D01*
X732075Y-269475D01*
X731605Y-268845D01*
X731292Y-268110D01*
X731135Y-267270D01*
Y-266430D01*
X731292Y-265590D01*
X731605Y-264855D01*
X732075Y-264225D01*
X732623Y-263805D01*
X733250Y-263700D01*
X733877Y-263805D01*
X734425Y-264225D01*
X734895Y-264855D01*
X735208Y-265590D01*
X735365Y-266430D01*
Y-267270D01*
X735208Y-268110D01*
X734895Y-268845D01*
X734425Y-269475D01*
X733877Y-269895D01*
X733250Y-270000D01*
G01X737592D02*
X739550Y-263700D01*
X741508Y-270000D01*
G01X740803Y-267795D02*
X738297D01*
G01X744283Y-270000D02*
Y-263700D01*
X746242D01*
X746868Y-264015D01*
X747260Y-264435D01*
X747417Y-265275D01*
X747260Y-266115D01*
X746790Y-266640D01*
X746242Y-266955D01*
X744283D01*
G01X746242D02*
X747417Y-270000D01*
G01X750427D02*
Y-263700D01*
X751993D01*
X752620Y-264015D01*
X753090Y-264435D01*
X753482Y-265065D01*
X753795Y-265800D01*
X753873Y-266850D01*
X753795Y-267900D01*
X753482Y-268635D01*
X753090Y-269265D01*
X752620Y-269685D01*
X751993Y-270000D01*
X750427D01*
G01X756100Y-272100D02*
X760800D01*
G01X762713Y-270000D02*
Y-263700D01*
X764750Y-268950D01*
X766787Y-263700D01*
Y-270000D01*
G01X769483D02*
Y-263700D01*
X771363D01*
X771990Y-264015D01*
X772460Y-264750D01*
X772617Y-265590D01*
X772460Y-266430D01*
X772068Y-267060D01*
X771363Y-267375D01*
X769483D01*
G01X775627Y-269055D02*
X776097Y-269580D01*
X776645Y-269895D01*
X777350Y-270000D01*
X778055Y-269790D01*
X778603Y-269370D01*
X778995Y-268635D01*
X779073Y-267795D01*
X778917Y-266955D01*
X778525Y-266430D01*
X777977Y-266010D01*
X777428Y-265905D01*
X776880Y-266010D01*
X776175Y-266430D01*
X776410Y-263700D01*
X778525D01*
G01X783650D02*
X783023Y-263910D01*
X782553Y-264435D01*
X782240Y-265065D01*
X782005Y-265905D01*
X781927Y-266850D01*
X782005Y-267795D01*
X782240Y-268635D01*
X782553Y-269265D01*
X783023Y-269790D01*
X783650Y-270000D01*
X784277Y-269790D01*
X784747Y-269265D01*
X785060Y-268635D01*
X785295Y-267795D01*
X785373Y-266850D01*
X785295Y-265905D01*
X785060Y-265065D01*
X784747Y-264435D01*
X784277Y-263910D01*
X783650Y-263700D01*
G01X790890Y-270000D02*
Y-263700D01*
X787992Y-268215D01*
X791908D01*
G01X796250Y-270000D02*
X796798Y-269895D01*
X797425Y-269580D01*
X797817Y-269055D01*
X797973Y-268320D01*
X797817Y-267585D01*
X797347Y-266955D01*
X796642Y-266640D01*
X795858D01*
X795388Y-266430D01*
X794997Y-265905D01*
X794840Y-265170D01*
X795075Y-264435D01*
X795623Y-263910D01*
X796250Y-263700D01*
X796877Y-263910D01*
X797425Y-264435D01*
X797660Y-265170D01*
X797503Y-265905D01*
X797112Y-266430D01*
X796642Y-266640D01*
X795858D01*
X795153Y-266955D01*
X794683Y-267585D01*
X794527Y-268320D01*
X794683Y-269055D01*
X795075Y-269580D01*
X795702Y-269895D01*
X796250Y-270000D01*
G01X738322Y-319959D02*
Y-311959D01*
X737122Y-313559D01*
G01Y-319959D02*
X739522D01*
G01X744422Y-316626D02*
X745122Y-315692D01*
X745722Y-315159D01*
X746522Y-314892D01*
X747222Y-315159D01*
X747722Y-315692D01*
X748122Y-316492D01*
X748222Y-317426D01*
X748122Y-318226D01*
X747722Y-319026D01*
X747122Y-319692D01*
X746422Y-319959D01*
X745622Y-319692D01*
X744922Y-318893D01*
X744522Y-317692D01*
X744422Y-316359D01*
X744622Y-314626D01*
X744922Y-313692D01*
X745422Y-312759D01*
X746122Y-312092D01*
X746822Y-311959D01*
X747522Y-312226D01*
X748022Y-312892D01*
G01X754322Y-320226D02*
X754122Y-320092D01*
Y-319826D01*
X754322Y-319692D01*
X754522Y-319826D01*
Y-320092D01*
X754322Y-320226D01*
G01X760422Y-316626D02*
X761122Y-315692D01*
X761722Y-315159D01*
X762522Y-314892D01*
X763222Y-315159D01*
X763722Y-315692D01*
X764122Y-316492D01*
X764222Y-317426D01*
X764122Y-318226D01*
X763722Y-319026D01*
X763122Y-319692D01*
X762422Y-319959D01*
X761622Y-319692D01*
X760922Y-318893D01*
X760522Y-317692D01*
X760422Y-316359D01*
X760622Y-314626D01*
X760922Y-313692D01*
X761422Y-312759D01*
X762122Y-312092D01*
X762822Y-311959D01*
X763522Y-312226D01*
X764022Y-312892D01*
G01X783322Y-319959D02*
Y-311959D01*
X782122Y-313559D01*
G01Y-319959D02*
X784522D01*
G01X791122D02*
X791322Y-318226D01*
X791622Y-316759D01*
X792022Y-315426D01*
X792522Y-313959D01*
X793322Y-311959D01*
X789322D01*
G01X799322Y-320226D02*
X799122Y-320092D01*
Y-319826D01*
X799322Y-319692D01*
X799522Y-319826D01*
Y-320092D01*
X799322Y-320226D01*
G01X805422Y-313292D02*
X806022Y-312492D01*
X806722Y-312092D01*
X807522Y-311959D01*
X808522Y-312226D01*
X809222Y-312892D01*
X809422Y-313692D01*
X809322Y-314493D01*
X808922Y-315159D01*
X806922Y-316492D01*
X806022Y-317426D01*
X805422Y-318759D01*
X805222Y-319959D01*
X809422D01*
G01X803122Y-294959D02*
Y-286959D01*
X805122D01*
X805922Y-287359D01*
X806522Y-287892D01*
X807022Y-288692D01*
X807422Y-289626D01*
X807522Y-290959D01*
X807422Y-292292D01*
X807022Y-293226D01*
X806522Y-294026D01*
X805922Y-294559D01*
X805122Y-294959D01*
X803122D01*
G54D13*
G01X-32318Y1152816D02*
Y858267D01*
X-31121Y857070D01*
X-23500D01*
X-22318Y858252D01*
Y1152816D01*
M02*
